5
5
4
4
3
3
2
2
1
1
D D
C C
B B
A A
GRABD TETON_FAN_BP
COVER PAGE
PCB Thickness:  
PCB Layer:  
PCB size:  
1.6
51.7*337
6L
SizeDoc NumberRevDate: SheetofReviewerDesignerDepartmentProject
Page TitleBU9<Doc> V00B Monday, August 28, 2023<Designer><Reviewer> 1 25<Title>COVER PAGESizeDoc NumberRevDate: SheetofReviewerDesignerDepartmentProject
Page TitleBU9<Doc> V00B Monday, August 28, 2023<Designer><Reviewer> 1 25<Title>COVER PAGESizeDoc NumberRevDate: SheetofReviewerDesignerDepartmentProject
Page TitleBU9<Doc> V00B Monday, August 28, 2023<Designer><Reviewer> 1 25<Title>COVER PAGE



5
5
4
4
3
3
2
2
1
1
D D
C C
B B
A A
INDEX
FAN_BP_BLOCK DAIGRAM
008
005
011
010
006
001
007
PAGE PAGE
COVER PAGE
003
002 INDEX
004
COMPONENT /FUNCTION
009
FAN_IC_MAX31790
FAN_IC_NCT7363Y
FAN_PWM_BUFFER_1
FAN_PWM_BUFFER_2
FRU
FAN_PRESENT_BUFFER_1
FAN_PRESENT_BUFFER_2
SIDEBAND_LINK
012 IO_EXP_FANBP
016
015
018
017
014
013
023
021
019
022
020
024
POWER_EN
PDBV_GF
EFUSE_1
EFUSE_2
EFUSE_3
LED_1
LED_2
FAN_CONN_1
FAN_CONN_2
ADC
VOLTAGE_SWITCH
SCREW
025 TDR
SizeDoc NumberRevDate: SheetofReviewerDesignerDepartmentProject
Page TitleBU9<Doc> V00B Friday, December 02, 2022<Designer><Reviewer> 2 25<Title>INDEXSizeDoc NumberRevDate: SheetofReviewerDesignerDepartmentProject
Page TitleBU9<Doc> V00B Friday, December 02, 2022<Designer><Reviewer> 2 25<Title>INDEXSizeDoc NumberRevDate: SheetofReviewerDesignerDepartmentProject
Page TitleBU9<Doc> V00B Friday, December 02, 2022<Designer><Reviewer> 2 25<Title>INDEX



5
5
4
4
3
3
2
2
1
1
D D
C C
B B
A A
SizeDoc NumberRevDate: SheetofReviewerDesignerDepartmentProject
Page TitleBU9<Doc> V00B Friday, December 02, 2022<Designer><Reviewer> 3 25<Title>FAN BP BLOCK DIAGRAMSizeDoc NumberRevDate: SheetofReviewerDesignerDepartmentProject
Page TitleBU9<Doc> V00B Friday, December 02, 2022<Designer><Reviewer> 3 25<Title>FAN BP BLOCK DIAGRAMSizeDoc NumberRevDate: SheetofReviewerDesignerDepartmentProject
Page TitleBU9<Doc> V00B Friday, December 02, 2022<Designer><Reviewer> 3 25<Title>FAN BP BLOCK DIAGRAM



5
5
4
4
3
3
2
2
1
1
D D
C C
B B
A A
ADDRESS 0X40
ADDRESS 0X5E
FAN_IC_MAX31790
BOM OPTION 1
SMB_PDBV_FAN_SDA4,5,8,11,12,13SMB_PDBV_FAN_SCL4,5,8,11,12,13SMB_PDBV_FAN_SDA4,5,8,11,12,13SMB_PDBV_FAN_SCL4,5,8,11,12,13FAN_0_PWM 5,6FAN_0_TACH_IL 5,20FAN_1_TACH_IL 5,20FAN_0_TACH_OL 5,20FAN_1_PWM 5,6FAN_1_TACH_OL 5,20FAN_2_PWM 5,6FAN_2_TACH_IL 5,20FAN_3_TACH_IL 5,20FAN_2_TACH_OL 5,20FAN_3_PWM 5,6FAN_3_TACH_OL 5,20FAN_4_PWM 5,7FAN_4_TACH_IL 5,21FAN_5_TACH_IL 5,21FAN_4_TACH_OL 5,21FAN_5_PWM 5,7FAN_5_TACH_OL 5,21FAN_6_PWM 5,7FAN_6_TACH_IL 5,21FAN_7_TACH_IL 5,21FAN_6_TACH_OL 5,21FAN_7_PWM 5,7FAN_7_TACH_OL 5,21
P3V3_AUXP3V3_AUXP3V3_AUXP3V3_AUX
P3V3_AUXP3V3_AUXP3V3_AUXP3V3_AUX
SizeDoc NumberRevDate: SheetofReviewerDesignerDepartmentProject
Page TitleBU9<Doc> V00B Monday, August 28, 2023<Designer><Reviewer> 4 25<Title>FAN_IC_MAX31790SizeDoc NumberRevDate: SheetofReviewerDesignerDepartmentProject
Page TitleBU9<Doc> V00B Monday, August 28, 2023<Designer><Reviewer> 4 25<Title>FAN_IC_MAX31790SizeDoc NumberRevDate: SheetofReviewerDesignerDepartmentProject
Page TitleBU9<Doc> V00B Monday, August 28, 2023<Designer><Reviewer> 4 25<Title>FAN_IC_MAX31790
C19380.1UF16VX7RC0402-020110%R5680 0R5607100Fan IC1_BOM0R5598 0Fan IC1_BOM0R4953220R0402-02015%NI R5618 0Fan IC1_BOM0R4947220R0402-02015%R4950220R0402-02015%C19320.1UF16VX7RC0402-020110%R5612 0Fan IC1_BOM0R5613100Fan IC1_BOM0R48494.7KR0402-02015%R5606 0Fan IC1_BOM0R5679 0R5600 0Fan IC1_BOM0R5459 33R47794.7KR0402-02015%NIR5620 0Fan IC1_BOM0R5603100Fan IC1_BOM0R4940220R0402-02015%NI
MAX31790ATI+TU330<Part Number>Fan IC1_BOM0FREQ_START1SPIN_START2ADD13ADD04WD_START5GND8TACH69TACH511TACH413TACH315TACH217TACH119PWMOUT610PWMOUT512PWMOUT414PWMOUT316PWMOUT218PWMOUT120VCC21SDA22SCL23FAN_FAIL#24PWM_START025PWM_START126FULL_SPEED#27CLKOUT28THTHXTAL26XTAL17R4949220R0402-02015%R4942220R0402-02015%NIR4952220R0402-02015%NIR4782220R0402-02015%R5617 0Fan IC1_BOM0R4936220R0402-02015%NI R5597100Fan IC1_BOM0
R4851220R0402-02015%NIR4946220R0402-02015%NI R5619100Fan IC1_BOM0R5608 0Fan IC1_BOM0R5614 0Fan IC1_BOM0R5605 0Fan IC1_BOM0R5611 0Fan IC1_BOM0R568110K1/16W1%R0402-0201R5609100Fan IC1_BOM0MAX31790ATI+TU317<Part Number>Fan IC1_BOM0FREQ_START1SPIN_START2ADD13ADD04WD_START5GND8TACH69TACH511TACH413TACH315TACH217TACH119PWMOUT610PWMOUT512PWMOUT414PWMOUT316PWMOUT218PWMOUT120VCC21SDA22SCL23FAN_FAIL#24PWM_START025PWM_START126FULL_SPEED#27CLKOUT28THTHXTAL26XTAL17R48484.7KR0402-02015%R5602 0Fan IC1_BOM0R4939220R0402-02015%R4944220R0402-02015%NIR4941220R0402-02015%R4937220R0402-02015%NI R5599 0Fan IC1_BOM0R47784.7KR0402-02015%NIR4954220R0402-02015%NIR4948220R0402-02015%R4951220R0402-02015%NI R5616 0Fan IC1_BOM0R4935220R0402-02015%R4938220R0402-02015%NIR568210K1/16W1%R0402-0201R4781220R0402-02015%R4945220R0402-02015%NIR5461 33R5615100Fan IC1_BOM0R4850220R0402-02015%NI
R5604 0Fan IC1_BOM0R5610 0Fan IC1_BOM0R5460 33R5458 33R4943220R0402-02015%R5601100Fan IC1_BOM0SMB_PDBV_FAN_R_U317_SDASMB_PDBV_FAN_R_U317_SCLMAX31790_U317_ADD1MAX31790_U317_ADD0SMB_PDBV_FAN_R_U330_SDASMB_PDBV_FAN_R_U330_SCLMAX31790_U330_ADD1MAX31790_U330_ADD0TP_U317_XTAL2TP_U317_XTAL1TP_U330_XTAL2TP_U330_XTAL1MAX31790_U317_SPIN_STARTMAX31790_U317_PWM_START1MAX31790_U317_PWM_START0MAX31790_U317_FREQ_STARTMAX31790_U317_WD_STARTMAX31790_U330_PWM_START1MAX31790_U330_PWM_START0MAX31790_U330_FREQ_STARTMAX31790_U330_SPIN_STARTMAX31790_U330_WD_START
MAX31790_U317_PWM_START1MAX31790_U317_PWM_START0MAX31790_U317_FREQ_STARTMAX31790_U317_SPIN_STARTMAX31790_U317_WD_STARTMAX31790_U330_PWM_START1MAX31790_U330_PWM_START0MAX31790_U330_FREQ_STARTMAX31790_U330_SPIN_STARTMAX31790_U330_WD_STARTU317_FAN FS_NU330_FAN FS_NNC_U330_CLKOUTNC_U317_CLKOUTFAN_0_PWM_R1FAN_0_TACH_IL_R1FAN_1_TACH_IL_R1FAN_0_TACH_OL_R1FAN_1_PWM_R1FAN_1_TACH_OL_R1FAN_2_PWM_R1FAN_2_TACH_IL_R1FAN_3_TACH_IL_R1FAN_2_TACH_OL_R1FAN_3_PWM_R1FAN_3_TACH_OL_R1FAN_4_PWM_R1FAN_4_TACH_IL_R1FAN_5_TACH_IL_R1FAN_4_TACH_OL_R1FAN_5_PWM_R1FAN_5_TACH_OL_R1FAN_6_PWM_R1FAN_6_TACH_IL_R1FAN_7_TACH_IL_R1FAN_6_TACH_OL_R1FAN_7_PWM_R1FAN_7_TACH_OL_R1
U317_FAN FAIL_NU330_FAN FAIL_N



5
5
4
4
3
3
2
2
1
1
D D
C C
B B
A A
FAN_IC_NCT7363Y
ADDRESS 0X02
ADDRESS 0X04
Colay Fan Controller, BOM option.
Colay Fan Controller, BOM option.
BOM OPTION 2
SMB_PDBV_FAN_SDA4,5,8,11,12,13SMB_PDBV_FAN_SCL4,5,8,11,12,13SMB_PDBV_FAN_SDA4,5,8,11,12,13SMB_PDBV_FAN_SCL4,5,8,11,12,13FAN_0_PWM 4,6FAN_0_TACH_IL 4,20FAN_1_TACH_IL 4,20FAN_0_TACH_OL 4,20FAN_1_PWM 4,6FAN_1_TACH_OL 4,20FAN_2_PWM 4,6FAN_2_TACH_IL 4,20FAN_3_TACH_IL 4,20FAN_2_TACH_OL 4,20FAN_3_PWM 4,6FAN_3_TACH_OL 4,20FAN_4_PWM 4,7FAN_4_TACH_IL 4,21FAN_5_TACH_IL 4,21FAN_4_TACH_OL 4,21FAN_5_PWM 4,7FAN_5_TACH_OL 4,21FAN_6_PWM 4,7FAN_6_TACH_IL 4,21FAN_7_TACH_IL 4,21FAN_6_TACH_OL 4,21FAN_7_PWM 4,7FAN_7_TACH_OL 4,21
P3V3_AUXP3V3_AUXP3V3_AUXP3V3_AUXSizeDoc NumberRevDate: SheetofReviewerDesignerDepartmentProject
Page TitleBU9<Doc> V00B Monday, August 28, 2023<Designer><Reviewer> 5 25<Title>FAN_IC_MAX31790SizeDoc NumberRevDate: SheetofReviewerDesignerDepartmentProject
Page TitleBU9<Doc> V00B Monday, August 28, 2023<Designer><Reviewer> 5 25<Title>FAN_IC_MAX31790SizeDoc NumberRevDate: SheetofReviewerDesignerDepartmentProject
Page TitleBU9<Doc> V00B Monday, August 28, 2023<Designer><Reviewer> 5 25<Title>FAN_IC_MAX31790
R5577 0Fan IC2_BOM1R5584 0Fan IC2_BOM1R55674.7KR0402-02015%NI R5589 0Fan IC2_BOM1U404NCT7363Y<Part Number>Fan IC2_BOM1GPIO00||PWM0||FANIN81GPIO01||PWM1||FANIN92GPIO02||PWM2||FANIN103GPIO03||PWM3||FANIN11||ALERT#4GPIO04||PWM4||FANIN125GPIO05||PWM5||FANIN136GPIO06||PWM6||FANIN147GPIO07||PWM7||FANIN15||ALERT#8VSS9GPIO10||PWM8||FANIN010GPIO11||PWM9||FANIN111GPIO12||PWM10||FANIN212A018GPIO17||PWM15||FANIN7||ALERT#17GPIO16||PWM14||FANIN616GPIO15||PWM13||FANIN515GPIO14||PWM12||FANIN414GPIO13||PWM11||FANIN3||ALERT#13A224A123INT#||LED||BEEP22VDD21SDA20SCL19THTHR5560220R0402-02015%NI R5578 0Fan IC2_BOM1
R5570220R0402-02015% R5590 0Fan IC2_BOM1R5568 33R5571220R0402-02015%NI R5591 0Fan IC2_BOM1R5579 0Fan IC2_BOM1R55614.7KR0402-02015%NIR5572220R0402-02015% R5592 0Fan IC2_BOM1R5569 33R5573 0Fan IC2_BOM1R55624.7KR0402-02015%NI R5580 0Fan IC2_BOM1R5593 0Fan IC2_BOM1R5557 33R5563220R0402-02015% R5574 0Fan IC2_BOM1C20940.1UF16VX7RC0402-020110%
R5594 0Fan IC2_BOM1R5581 0Fan IC2_BOM1R5564220R0402-02015%R5558 33U403NCT7363Y<Part Number>Fan IC2_BOM1GPIO00||PWM0||FANIN81GPIO01||PWM1||FANIN92GPIO02||PWM2||FANIN103GPIO03||PWM3||FANIN11||ALERT#4GPIO04||PWM4||FANIN125GPIO05||PWM5||FANIN136GPIO06||PWM6||FANIN147GPIO07||PWM7||FANIN15||ALERT#8VSS9GPIO10||PWM8||FANIN010GPIO11||PWM9||FANIN111GPIO12||PWM10||FANIN212A018GPIO17||PWM15||FANIN7||ALERT#17GPIO16||PWM14||FANIN616GPIO15||PWM13||FANIN515GPIO14||PWM12||FANIN414GPIO13||PWM11||FANIN3||ALERT#13A224A123INT#||LED||BEEP22VDD21SDA20SCL19THTHR5595 0Fan IC2_BOM1R5585 0Fan IC2_BOM1R5575 0Fan IC2_BOM1R5582 0Fan IC2_BOM1C20950.1UF16VX7RC0402-020110%R5596 0Fan IC2_BOM1R5586 0Fan IC2_BOM1R55654.7KR0402-02015%NI R5576 0Fan IC2_BOM1R5587 0Fan IC2_BOM1R5583 0Fan IC2_BOM1R55664.7KR0402-02015%R55594.7KR0402-02015% R5588 0Fan IC2_BOM1U403_ADD2U403_ADD1SMB_PDBV_FAN_R_U403_SDASMB_PDBV_FAN_R_U403_SCLU403_ADD0SMB_PDBV_FAN_R_U404_SDASMB_PDBV_FAN_R_U404_SCLU404_ADD2U404_ADD1U404_ADD0
FAN_0_PWM_R2FAN_0_TACH_IL_R2FAN_1_TACH_IL_R2FAN_0_TACH_OL_R2FAN_1_PWM_R2FAN_1_TACH_OL_R2FAN_2_PWM_R2FAN_2_TACH_IL_R2FAN_3_TACH_IL_R2FAN_2_TACH_OL_R2FAN_3_PWM_R2FAN_3_TACH_OL_R2FAN_4_PWM_R2FAN_4_TACH_IL_R2FAN_5_TACH_IL_R2FAN_4_TACH_OL_R2FAN_5_PWM_R2FAN_5_TACH_OL_R2FAN_6_PWM_R2FAN_6_TACH_IL_R2FAN_7_TACH_IL_R2FAN_6_TACH_OL_R2FAN_7_PWM_R2FAN_7_TACH_OL_R2NC_U403_P17NC_U403_P16NC_U403_P14NC_U403_P15NC_U404_P14NC_U404_P15NC_U404_P16NC_U404_P17NC_U404_P22NC_U403_P22



5
5
4
4
3
3
2
2
1
1
D D
C C
B B
A A
Remove reserved PU.
FAN PWM BUFFER1
FAN_0_PWM_IL 20FAN_0_PWM4,5 FAN_0_PWM_OL 20FAN_1_PWM_IL 20FAN_1_PWM4,5 FAN_1_PWM_OL 20FAN_2_PWM_IL 20FAN_2_PWM4,5 FAN_2_PWM_OL 20FAN_3_PWM_IL 20FAN_3_PWM4,5 FAN_3_PWM_OL 20
P3V3_AUXP3V3_AUXP3V3_AUXP3V3_AUXP3V3_AUX
P3V3_AUXP3V3_AUXP3V3_AUXP3V3_AUXP3V3_AUXP3V3_AUXP3V3_AUXSizeDoc NumberRevDate: SheetofReviewerDesignerDepartmentProject
Page TitleBU9<Doc> V00C Monday, August 28, 2023<Designer><Reviewer> 6 25<Title>FAN_PWM_BUFFERSizeDoc NumberRevDate: SheetofReviewerDesignerDepartmentProject
Page TitleBU9<Doc> V00C Monday, August 28, 2023<Designer><Reviewer> 6 25<Title>FAN_PWM_BUFFERSizeDoc NumberRevDate: SheetofReviewerDesignerDepartmentProject
Page TitleBU9<Doc> V00C Monday, August 28, 2023<Designer><Reviewer> 6 25<Title>FAN_PWM_BUFFER
OVTU60MC74VHC1G07DFT2G<Part Number>VCC5IN_A2GND3OUT_Y4NC11R3364.7K5%R0402-0201C1000.1UF10%16VC0402-0201X7RR55134.7K5%1/16WR0402-0201NIOVTU64MC74VHC1G07DFT2G<Part Number>VCC5IN_A2GND3OUT_Y4NC11U65BAT54CW-7-F<Part Number>213R3444.7K5%R0402-0201C20870.1UF10%16VC0402-0201X7RU67BAT54CW-7-F<Part Number>213R3524.7K5%R0402-0201R55124.7K5%1/16WR0402-0201NIR3604.7K5%R0402-0201OVTU66MC74VHC1G07DFT2G<Part Number>VCC5IN_A2GND3OUT_Y4NC11R55144.7K5%1/16WR0402-0201NIC20880.1UF10%16VC0402-0201X7RR55114.7K5%1/16WR0402-0201NI
C20890.1UF10%16VC0402-0201X7ROVTU62MC74VHC1G07DFT2G<Part Number>VCC5IN_A2GND3OUT_Y4NC11U61BAT54CW-7-F<Part Number>213U63BAT54CW-7-F<Part Number>213FAN_0_PWMFAN_0_PWM_BUFFAN_1_PWMFAN_1_PWM_BUFFAN_2_PWM_BUFFAN_3_PWMFAN_3_PWM_BUFFAN_2_PWMNC_U60_P1NC_U62_P1NC_U64_P1NC_U66_P1



5
5
4
4
3
3
2
2
1
1
D D
C C
B B
A A
FAN PWM BUFFER2
Remove reserved PU.
FAN_4_PWM_IL 21FAN_4_PWM_OL 21FAN_5_PWM_IL 21FAN_5_PWM_OL 21FAN_6_PWM_IL 21FAN_6_PWM_OL 21FAN_7_PWM_IL 21FAN_7_PWM_OL 21
FAN_4_PWM4,5FAN_5_PWM4,5FAN_6_PWM4,5FAN_7_PWM4,5
P3V3_AUXP3V3_AUXP3V3_AUXP3V3_AUX
P3V3_AUXP3V3_AUXP3V3_AUXP3V3_AUXP3V3_AUXP3V3_AUXP3V3_AUXP3V3_AUXSizeDoc NumberRevDate: SheetofReviewerDesignerDepartmentProject
Page TitleBU9<Doc> V00C Monday, August 28, 2023<Designer><Reviewer> 7 25<Title>FAN_PWM_BUFFER_2SizeDoc NumberRevDate: SheetofReviewerDesignerDepartmentProject
Page TitleBU9<Doc> V00C Monday, August 28, 2023<Designer><Reviewer> 7 25<Title>FAN_PWM_BUFFER_2SizeDoc NumberRevDate: SheetofReviewerDesignerDepartmentProject
Page TitleBU9<Doc> V00C Monday, August 28, 2023<Designer><Reviewer> 7 25<Title>FAN_PWM_BUFFER_2
R55204.7K5%R0402-0201R55164.7K5%1/16WR0402-0201NIOVTU400MC74VHC1G07DFT2G<Part Number>VCC5IN_A2GND3OUT_Y4NC11R55194.7K5%R0402-0201
R55224.7K5%R0402-0201C20910.1UF10%16VC0402-0201X7RR55184.7K5%1/16WR0402-0201NI
R55154.7K5%1/16WR0402-0201NI
OVTU402MC74VHC1G07DFT2G<Part Number>VCC5IN_A2GND3OUT_Y4NC11
C20900.1UF10%16VC0402-0201X7R
C20930.1UF10%16VC0402-0201X7R
U323BAT54CW-7-F<Part Number>213U325BAT54CW-7-F<Part Number>213R55214.7K5%R0402-0201U327BAT54CW-7-F<Part Number>213OVTU399MC74VHC1G07DFT2G<Part Number>VCC5IN_A2GND3OUT_Y4NC11R55174.7K5%1/16WR0402-0201NIU329BAT54CW-7-F<Part Number>213OVTU401MC74VHC1G07DFT2G<Part Number>VCC5IN_A2GND3OUT_Y4NC11C20920.1UF10%16VC0402-0201X7RFAN_4_PWM_BUFFAN_5_PWM_BUFFAN_6_PWM_BUFFAN_7_PWM_BUF
FAN_4_PWMFAN_5_PWMFAN_6_PWMFAN_7_PWM
NC_U399_P1NC_U400_P1NC_U401_P1NC_U402_P1



5
5
4
4
3
3
2
2
1
1
D D
C C
B B
A A
ADDRESS 0XAC
FRU
FRU
SMB_PDBV_FAN_SDA 4,5,11,12,13SMB_PDBV_FAN_SCL 4,5,11,12,13P3V3_AUXP3V3_AUXP3V3_AUX
SizeDoc NumberRevDate: SheetofReviewerDesignerDepartmentProject
Page TitleBU9<Doc> V00B Monday, August 28, 2023<Designer><Reviewer> 8 25<Title>FRUSizeDoc NumberRevDate: SheetofReviewerDesignerDepartmentProject
Page TitleBU9<Doc> V00B Monday, August 28, 2023<Designer><Reviewer> 8 25<Title>FRUSizeDoc NumberRevDate: SheetofReviewerDesignerDepartmentProject
Page TitleBU9<Doc> V00B Monday, August 28, 2023<Designer><Reviewer> 8 25<Title>FRU
R30910K1/16W1%R0402R313 05% R0402-0201C930.1UFC0402-020110%16VX7RR314 05% R0402-0201R3104.7KR0402-02015%R3114.7KR0402-02015%R315220R0402-02015%NIR3124.7KR0402-02015%NIR3081K1/16W1%R0402-0201NIR316220R0402-02015%NIR317220R0402-02015%U59M24256-BRMN6TP<Part Number>WC_N7E01E12E23SDA5SCL6VCC8VSS4FRU_WP_NFRU_ADDR0SMB_FRU_DATSMB_PDBV_FAN_SDAFRU_ADDR1SMB_FRU_CLKSMB_PDBV_FAN_SCLFRU_ADDR2



5
5
4
4
3
3
2
2
1
1
D D
C C
B B
A A
FAN 1 PRESENT
CAD Note: Place Resistors near 74LVC2G17GW
FAN 0 PRESENT
FAN 2 PRESENT
CAD Note: Place Resistors near 74LVC2G17GW
FAN 3 PRESENT
CAD Note: Place Resistors near 74LVC2G17GW
CAD Note: Place Resistors near 74LVC2G17GW
EVT: Change serial resistor to 240 ohm
EVT: Change to 0402 (CE Comment)
EVT: Change serial resistor to 240 ohm
EVT: Change to 0402 (CE Comment)
EVT: Change serial resistor to 240 ohm
EVT: Change to 0402 (CE Comment)
EVT: Change serial resistor to 240 ohm
EVT: Change to 0402 (CE Comment)
FAN PRESENT BUFFER1
FAN_0_PRESENT_R_N20 FAN_0_PRSNT_BUF_N 12,15FAN_1_PRESENT_R_N20 FAN_1_PRSNT_BUF_N 12,15FAN_2_PRESENT_R_N20 FAN_2_PRSNT_BUF_N 12,15FAN_3_PRESENT_R_N20 FAN_3_PRSNT_BUF_N 12,16
P3V3_AUXP3V3_AUXP3V3_AUXP3V3_AUXP3V3_AUXP3V3_AUXP3V3_AUXP3V3_AUXP3V3_AUXP3V3_AUXP3V3_AUXP3V3_AUXSizeDoc NumberRevDate: SheetofReviewerDesignerDepartmentProject
Page TitleBU9<Doc> V00B Monday, August 28, 2023<Designer><Reviewer> 9 25<Title>FAN_PRESENT_BUFFERSizeDoc NumberRevDate: SheetofReviewerDesignerDepartmentProject
Page TitleBU9<Doc> V00B Monday, August 28, 2023<Designer><Reviewer> 9 25<Title>FAN_PRESENT_BUFFERSizeDoc NumberRevDate: SheetofReviewerDesignerDepartmentProject
Page TitleBU9<Doc> V00B Monday, August 28, 2023<Designer><Reviewer> 9 25<Title>FAN_PRESENT_BUFFERR10110K1/16W1%R0402-0201
R9810K1/16W1%R0402-0201
R104 2401% R0402-0201U23-274LVC2G17GW3425R5495 1001%1/16W R0402-0201R5497 1001%1/16W R0402-0201U24-174LVC2G17GW<Part Number>1625R103 2401% R0402-0201U24-274LVC2G17GW3425C550.1UF10%16VC0402-0201X7R
C510.1UF10%16VC0402-0201X7RR55074.7K5%1/16WR0402-0201
C56100NFR5498 1001%1/16W R0402-0201
R55084.7K5%1/16WR0402-0201C52100NFR55094.7K5%1/16WR0402-0201R105 2401% R0402-0201R10210K1/16W1%R0402-0201
R9910K1/16W1%R0402-0201C54100NFR55104.7K5%1/16WR0402-0201R5496 1001%1/16W R0402-0201R100 2401% R0402-0201
C570.1UF10%16VC0402-0201X7R
C530.1UF10%16VC0402-0201X7RU23-174LVC2G17GW<Part Number>1625
C58100NF
FAN_0_PRESENT_NFAN_0_PRSNT_BUF_R_NFAN_0_PRSNT_BUF_NFAN_1_PRESENT_NFAN_1_PRSNT_BUF_R_NFAN_1_PRSNT_BUF_NFAN_2_PRESENT_NFAN_2_PRSNT_BUF_R_NFAN_2_PRSNT_BUF_NFAN_3_PRESENT_NFAN_3_PRSNT_BUF_R_NFAN_3_PRSNT_BUF_N



5
5
4
4
3
3
2
2
1
1
D D
C C
B B
A A
EVT: Change serial resistor to 240 ohm
CAD Note: Place Resistors near 74LVC2G17GW
EVT: Change to 0402 (CE Comment)
EVT: Change to 0402 (CE Comment)
EVT: Change to 0402 (CE Comment)
EVT: Change to 0402 (CE Comment)
FAN 7 PRESENT
FAN 6 PRESENT
FAN 4 PRESENT
FAN 5 PRESENT
CAD Note: Place Resistors near 74LVC2G17GW
CAD Note: Place Resistors near 74LVC2G17GW
CAD Note: Place Resistors near 74LVC2G17GW
EVT: Change serial resistor to 240 ohm
EVT: Change serial resistor to 240 ohm
EVT: Change serial resistor to 240 ohm
FAN PRESENT BUFFER2
FAN_4_PRESENT_R_N21 FAN_4_PRSNT_BUF_N 12,16FAN_5_PRESENT_R_N21 FAN_5_PRSNT_BUF_N 12,16FAN_6_PRESENT_R_N21 FAN_6_PRSNT_BUF_N 12,17FAN_7_PRESENT_R_N21 FAN_7_PRSNT_BUF_N 12,17
P3V3_AUXP3V3_AUXP3V3_AUXP3V3_AUXP3V3_AUXP3V3_AUXP3V3_AUXP3V3_AUXP3V3_AUXP3V3_AUXP3V3_AUXP3V3_AUXSizeDoc NumberRevDate: SheetofReviewerDesignerDepartmentProject
Page TitleBU9<Doc> V00B Monday, August 28, 2023<Designer><Reviewer> 10 25<Title>FAN_PRESENT_BUFFER_2SizeDoc NumberRevDate: SheetofReviewerDesignerDepartmentProject
Page TitleBU9<Doc> V00B Monday, August 28, 2023<Designer><Reviewer> 10 25<Title>FAN_PRESENT_BUFFER_2SizeDoc NumberRevDate: SheetofReviewerDesignerDepartmentProject
Page TitleBU9<Doc> V00B Monday, August 28, 2023<Designer><Reviewer> 10 25<Title>FAN_PRESENT_BUFFER_2C19450.1UF10%16VC0402-0201X7RU26-274LVC2G17GW3425R4863 2401% R0402-0201
R55034.7K5%1/16WR0402-0201C19410.1UF10%16VC0402-0201X7RR4855 2401% R0402-0201R55054.7K5%1/16WR0402-0201R5500 1001%1/16W R0402-0201C1940100NFC1946100NFR486010K1/16W1%R0402-0201R4867 2401% R0402-0201
R485210K1/16W1%R0402-0201C19430.1UF10%16VC0402-0201X7RR4859 2401% R0402-0201R5501 1001%1/16W R0402-0201R55044.7K5%1/16WR0402-0201C1942100NFC1948100NFR55064.7K5%1/16WR0402-0201
C19390.1UF10%16VC0402-0201X7R
R486410K1/16W1%R0402-0201
R5499 1001%1/16W R0402-0201U25-174LVC2G17GW<Part Number>1625
R5502 1001%1/16W R0402-0201
R485610K1/16W1%R0402-0201U25-274LVC2G17GW3425U26-174LVC2G17GW<Part Number>1625FAN_4_PRESENT_NFAN_4_PRSNT_BUF_R_NFAN_4_PRSNT_BUF_NFAN_5_PRESENT_NFAN_5_PRSNT_BUF_R_NFAN_5_PRSNT_BUF_NFAN_6_PRESENT_NFAN_6_PRSNT_BUF_R_NFAN_6_PRSNT_BUF_NFAN_7_PRESENT_NFAN_7_PRSNT_BUF_R_NFAN_7_PRSNT_BUF_N



5
5
4
4
3
3
2
2
1
1
D D
C C
B B
A A
U321 TCA9548 ADDRESS:0XE0 [1 1 1 0 A2 A1 A0 0]
SIDEBAND_LINK
RST_SMB_PDB_N11,13SMB_FAN0_SCL 20SMB_FAN0_SDA 20SMB_FAN1_SCL 20SMB_FAN1_SDA 20SMB_FAN2_SCL 20SMB_FAN2_SDA 20SMB_FAN3_SCL 20SMB_FAN3_SDA 20SMB_FAN4_SCL 21SMB_FAN4_SDA 21SMB_FAN5_SCL 21SMB_FAN5_SDA 21SMB_FAN6_SCL 21SMB_FAN6_SDA 21SMB_FAN7_SCL 21SMB_FAN7_SDA 21SMB_PDBV_FAN_SDA4,5,8,12,13SMB_PDBV_FAN_SCL4,5,8,12,13RST_SMB_PDB_N11,13P3V3_AUXP3V3_AUX
P3V3_AUXP3V3_AUX
SizeDoc NumberRevDate: SheetofReviewerDesignerDepartmentProject
Page TitleBU9<Doc> V00B Monday, August 28, 2023<Designer><Reviewer> 11 25<Title>010_SIDEBAND_LINKSizeDoc NumberRevDate: SheetofReviewerDesignerDepartmentProject
Page TitleBU9<Doc> V00B Monday, August 28, 2023<Designer><Reviewer> 11 25<Title>010_SIDEBAND_LINKSizeDoc NumberRevDate: SheetofReviewerDesignerDepartmentProject
Page TitleBU9<Doc> V00B Monday, August 28, 2023<Designer><Reviewer> 11 25<Title>010_SIDEBAND_LINK
R4790 05% R0402-0201NIR5281 4.7K5% R0402-0201R55234.7KNI
U321PCA9548APW<Part Number>NIA01A12RESET#3SCL22SDA23VSS12VDD24SD04SC05SD16SC17SD28SC29SD310SC311SC414SD413SC516SD515SC618SD617SC720SD719A221R4877 05% R0402-0201NIR572100KR0402-02011%1/16WR4786 05% R0402-0201NIR5270 4.7K5% R0402-0201R5276 4.7K5% R0402-0201R5282 4.7K5% R0402-0201R54704.7KR55244.7KR54734.7KNIR4883 05% R0402-0201NIR5271 4.7K5% R0402-0201R4878 05% R0402-0201NIC19330.1UF16VX7RC0402-020110%R5462 33NIR5277 4.7K5% R0402-0201R5269 4.7K5% R0402-0201R4791 05% R0402-0201NIR4884 05% R0402-0201NIR4874 05% R0402-0201NIR5278 4.7K5% R0402-0201R4787 05% R0402-0201NIR5283 4.7K5% R0402-0201R4879 05% R0402-0201NIR5272 4.7K5% R0402-0201R4789 05% R0402-0201NIR5279 4.7K5% R0402-0201R5463 33NIR5288 4.7K5% R0402-0201R4792 05% R0402-0201NIR5273 4.7K5% R0402-0201R4785 05% R0402-0201NIR4880 05% R0402-0201NIR4876 05% R0402-0201NIR54714.7KR5274 4.7K5% R0402-0201R5645 05%R0402-0201R5280 4.7K5% R0402-0201R4788 05% R0402-0201NIR54724.7KNIR5275 4.7K5% R0402-0201SMB_FAN0_R_SCLSMB_FAN0_R_SDASMB_FAN1_R_SCLSMB_FAN1_R_SDASMB_FAN2_R_SCLSMB_FAN2_R_SDASMB_FAN3_R_SCLSMB_FAN3_R_SDAPD_TCA9548_SML1_U321_A2SMB_FAN4_R_SCLSMB_FAN4_R_SDASMB_FAN5_R_SCLSMB_FAN5_R_SDASMB_FAN6_R_SCLSMB_FAN6_R_SDASMB_FAN7_R_SCLSMB_FAN7_R_SDASMB_FAN5_R_SCLSMB_FAN5_R_SDASMB_FAN6_R_SCLSMB_FAN6_R_SDASMB_FAN7_R_SCLSMB_FAN7_R_SDASMB_FAN0_R_SCLSMB_FAN0_R_SDASMB_FAN1_R_SCLSMB_FAN1_R_SDASMB_FAN2_R_SCLSMB_FAN2_R_SDASMB_FAN3_R_SCLSMB_FAN4_R_SDAPD_TCA9548_SML1_U321_A1PD_TCA9548_SML1_U321_A0PD_TCA9548_SML1_U321_A2PD_TCA9548_SML1_U321_A1PD_TCA9548_SML1_U321_A0SMB_PDBV_FAN_R_U321_SDASMB_PDBV_FAN_R_U321_SCLSMB_FAN3_R_SDASMB_FAN4_R_SCLRST_SMB_PDB_R_N



5
5
4
4
3
3
2
2
1
1
D D
C C
B B
A A
U7 PCA9555 ADDRESS:0X42 [0 1 0 0 A2 A1 A0 0]
U8 PCA9552 ADDRESS:0XC4 [1 1 0 0 A2 A1 A0 0]
IO_EXP_FANBP
PLATFORM ID DEFINATIONBOARD ID DEFINATION
SMB_PDBV_FAN_SDA4,5,8,11,12,13
SMB_PDBV_FAN_SDA4,5,8,11,12,13SMB_PDBV_FAN_SCL4,5,8,11,12,13
SMB_PDBV_FAN_SCL4,5,8,11,12,13Fan_0_OK_R_LED 18Fan_0_FAIL_R_LED 18Fan_1_OK_R_LED 18Fan_1_FAIL_R_LED 18Fan_2_OK_R_LED 18Fan_2_FAIL_R_LED 18Fan_3_OK_R_LED 18Fan_3_FAIL_R_LED 18Fan_4_OK_R_LED 19Fan_4_FAIL_R_LED 19Fan_5_OK_R_LED 19Fan_5_FAIL_R_LED 19Fan_6_OK_R_LED 19Fan_6_FAIL_R_LED 19Fan_7_OK_R_LED 19Fan_7_FAIL_R_LED 19
FAN_0_PRSNT_BUF_N 9,15FAN_1_PRSNT_BUF_N 9,15FAN_2_PRSNT_BUF_N 9,15FAN_3_PRSNT_BUF_N 9,16FAN_4_PRSNT_BUF_N 10,16FAN_5_PRSNT_BUF_N 10,16FAN_6_PRSNT_BUF_N 10,17FAN_7_PRSNT_BUF_N 10,17P3V3_AUXP3V3_AUXP3V3_AUX
P3V3_AUXP3V3_AUXP3V3_AUXP3V3_AUXP3V3_AUX
SizeDoc NumberRevDate: SheetofReviewerDesignerDepartmentProject
Page TitleBU9<Doc> V00B Monday, August 28, 2023<Designer><Reviewer> 12 25<Title>IO_EXP_FANBPSizeDoc NumberRevDate: SheetofReviewerDesignerDepartmentProject
Page TitleBU9<Doc> V00B Monday, August 28, 2023<Designer><Reviewer> 12 25<Title>IO_EXP_FANBPSizeDoc NumberRevDate: SheetofReviewerDesignerDepartmentProject
Page TitleBU9<Doc> V00B Monday, August 28, 2023<Designer><Reviewer> 12 25<Title>IO_EXP_FANBPR5099 05% R0402-0201
R5466 33R56871KR0402-02011%NIR51131K1%R0402-0201R5095 05% R0402-0201R5104 05% R0402-0201R56881K1%R0402-0201NIR51141KR0402-02011%NI R56701K1%R0402-0201NIR5100 05% R0402-0201R5110 05% R0402-0201R56711K1%R0402-0201NIR23541KR0402-02011%NI C15020.1UFC0402-020125V
R5096 05% R0402-0201C20100.1UFC0402-020125VR5105 05% R0402-0201R56721KR0402-02011%NIR23551KR0402-02011%R56831K1%R0402-0201NIR5467 33R23621K1%R0402-0201U8PCA9552PW<Part Number>VDD24VSS12RESET-21A01A12A23SDA23SCL22P004P015P026P037P048P059P0610P0711P0813P0914P1015P1116P1217P1318P1419P1520R509310KR0402-02011%R5111 05% R0402-0201R5097 05% R0402-0201R5101 05% R0402-0201R56841K1%R0402-0201R54864.7KR23601K1%R0402-0201
R51151KR0402-02011%
U7PCA9555<Part Number>VDD24VSS12INT1SDA23SCL22P004P015P026P037P048P059P0610P0711P1013P1114P1215P1316P1417P1518P1619P1720A021A12A23R56851KR0402-02011%R5107 05% R0402-0201
R23611K1%R0402-0201NI
R51161KR0402-02011%NI R56731KR0402-02011%R5098 05% R0402-0201R5102 05% R0402-0201R5468 33
R23561KR0402-02011%NI
R51171K1%R0402-0201R56741KR0402-02011%R5094 05% R0402-0201R56751K1%R0402-0201R5108 05% R0402-0201R5103 05% R0402-0201R51121K1%R0402-0201NIR56861KR0402-02011%R5469 33
FAN_0_PRSNT_BUF_NFAN_1_PRSNT_BUF_NFAN_2_PRSNT_BUF_NPU_U7_PIN2FAN_3_PRSNT_BUF_NFAN_4_PRSNT_BUF_NPCA9555_MB0_A0FAN_5_PRSNT_BUF_NPCA9555_MB0_A1FAN_6_PRSNT_BUF_NPCA9555_MB0_A2FAN_7_PRSNT_BUF_NFM_BOARD_SKU_ID0FM_BOARD_SKU_ID1FM_BOARD_SKU_ID2TP_U7_PIN16SMB_PDBV_FAN_R_IOX_SDASMB_PDBV_FAN_R_IOX_SCLPCA9555_MB0_A0PCA9555_MB0_A1PCA9555_MB0_A2
Fan_0_OK_LEDFan_0_FAIL_LEDFan_1_OK_LEDFan_1_FAIL_LEDFan_2_OK_LEDPCA9552_MB1_A0Fan_2_FAIL_LEDPCA9552_MB1_A1Fan_3_OK_LEDPCA9552_MB1_A2Fan_3_FAIL_LEDFan_4_OK_LEDFan_4_FAIL_LEDFan_5_OK_LEDFan_5_FAIL_LEDSMB_PDBV_FAN_R1_IOX_SDAFan_6_OK_LEDFan_6_FAIL_LEDSMB_PDBV_FAN_R1_IOX_SCLFan_7_OK_LEDFan_7_FAIL_LEDPCA9552_MB1_A0PCA9552_MB1_A1PCA9552_MB1_A2PU_U8_PIN2FM_BOARD_SKU_ID0FM_BOARD_SKU_ID1FM_BOARD_SKU_ID2FM_BOARD_ID0FM_BOARD_ID1FM_BOARD_ID2FM_BOARD_ID0FM_BOARD_ID1FM_BOARD_ID2TP_U7_PIN20



5
5
4
4
3
3
2
2
1
1
D D
C C
B B
A A
PDBV_GF
SMB_PDBV_FAN_SDA4,5,8,11,12SMB_PDBV_FAN_SCL4,5,8,11,12RST_SMB_PDB_N 11P52V_FAN_EN 14P3V3_AUXP12V_LEDP3V3_AUXP52V_HSC
SizeDoc NumberRevDate: SheetofReviewerDesignerDepartmentProject
Page TitleBU9<Doc> V00B Monday, August 28, 2023<Designer><Reviewer> 13 25<Title>PDBV_GFSizeDoc NumberRevDate: SheetofReviewerDesignerDepartmentProject
Page TitleBU9<Doc> V00B Monday, August 28, 2023<Designer><Reviewer> 13 25<Title>PDBV_GFSizeDoc NumberRevDate: SheetofReviewerDesignerDepartmentProject
Page TitleBU9<Doc> V00B Monday, August 28, 2023<Designer><Reviewer> 13 25<Title>PDBV_GF
R4970 200R49894.7K5%NIR4968 05% R0402-0201R4969 05% R0402-0201R49884.7K5%NIGF1FCONN10_10121505-000408BLF<Part Number>NIS2S2S3S3S1S1S7S7S8S8S4S4S5S5S6S6P3_P4P3_P4P1_P2P1_P2SMB_PDBV_FAN_R_SCLP52V_FAN_EN_RSMB_PDBV_FAN_R_SDA



5
5
4
4
3
3
2
2
1
1
D D
C C
B B
A A
U84 is positive open-drainbuffer:
POWER_EN
P52V_FAN_EN13,14P52V_FAN_EN13,14P52V_FAN_0_BUFF_EN_R 15P52V_FAN_1_BUFF_EN_R 15P52V_FAN_2_BUFF_EN_R 15P52V_FAN_3_BUFF_EN_R 16P52V_FAN_4_BUFF_EN_R 16P52V_FAN_5_BUFF_EN_R 16P52V_FAN_6_BUFF_EN_R 17P52V_FAN_7_BUFF_EN_R 17
P3V3_AUXP3V3_AUXP3V3_AUXP3V3_AUXP3V3_AUXP3V3_AUX
P3V3_AUXP3V3_AUX
SizeDoc NumberRevDate: SheetofReviewerDesignerDepartmentProject
Page TitleBU9<Doc> V00C Monday, August 28, 2023<Designer><Reviewer> 14 25<Title>POWER_ENSizeDoc NumberRevDate: SheetofReviewerDesignerDepartmentProject
Page TitleBU9<Doc> V00C Monday, August 28, 2023<Designer><Reviewer> 14 25<Title>POWER_ENSizeDoc NumberRevDate: SheetofReviewerDesignerDepartmentProject
Page TitleBU9<Doc> V00C Monday, August 28, 2023<Designer><Reviewer> 14 25<Title>POWER_EN
C20810.033UFU389A74LVC07APW<Part Number>12147U390E74LVC07APW1110C20840.1UFC20800.015UF
R5494 33
R513 0
U389B74LVC07APW34U390F74LVC07APW1312R49581K1/16W1%R0402-0201R5121K1/16W1%R0402-0201R49571K1/16W1%R0402-0201U389C74LVC07APW56
R5488 33R519 10KR0402-0201 1%C188 0.1UFX7R C0402-020110% 16V
U389D74LVC07APW98R5491 33U389E74LVC07APW1110
R5111K1/16W1%R0402-0201R520 10KR0402-0201 1%NIR49561K1/16W1%R0402-0201U389F74LVC07APW1312
R5489 33R49551K1/16W1%R0402-0201R5492 33R521 10KR0402-0201 1%R4966 10KR0402-0201 1%NI
R5487 33R5490 33R4959 0U390A74LVC07APW<Part Number>12147R518 10KR0402-0201 1%NIR4964 10KR0402-0201 1%NIC20820.056UFU390B74LVC07APW34
R5493 33R4967 10KR0402-0201 1%
U390C74LVC07APW56R5101K1/16W1%R0402-0201
C20830.082UFR4965 10KR0402-0201 1%C20860.47UFC20850.22UFU390D74LVC07APW98C1953 0.1UFX7R C0402-020110% 16VR5091K1/16W1%R0402-0201P52V_FAN_BUFF_EN_RP52V_FAN_1_BUFF_ENP52V_FAN_2_BUFF_ENP52V_FAN_3_BUFF_ENPD_FAN_BUFF_INPUT_U336EPD_FAN_BUFF_INPUT_U336FP52V_FAN_BUFF_EN_RP52V_FAN_4_BUFF_ENP52V_FAN_5_BUFF_ENP52V_FAN_6_BUFF_ENPD_FAN_BUFF_INPUT_U337EPD_FAN_BUFF_INPUT_U337F
P52V_FAN_0_BUFF_EN
P52V_FAN_7_BUFF_ENNC_U389_FNC_U389_ENC_U390_ENC_U390_F



5
5
4
4
3
3
2
2
1
1
D D
C C
B B
A A
EFUSE1
MODE:PULL MODE HIGH FOR LATCH MODEPULL MODE DOWN FOR HICCUP MODE
MODE:PULL MODE HIGH FOR LATCH MODEPULL MODE DOWN FOR HICCUP MODEMODE:PULL MODE HIGH FOR LATCH MODEPULL MODE DOWN FOR HICCUP MODE
Main(MP5048)Soft start: 25msIMax: 2AOCP(min/nom/max): 5.84/6.05/6.26A
Main(MP5048)Soft start: 25msIMax: 2AOCP(min/nom/max): 5.84/6.05/6.26A
Main(MP5048)Soft start: 25msIMax: 2AOCP(min/nom/max): 5.84/6.05/6.26A
FAN_0_PRSNT_BUF_N 9,12FAN_1_PRSNT_BUF_N 9,12FAN_2_PRSNT_BUF_N 9,12
P52V_FAN_0_BUFF_EN_R 14P52V_FAN_1_BUFF_EN_R 14P52V_FAN_2_BUFF_EN_R 14
FAN_0_PRESENT15,22FAN_0_PRESENT 15,22FAN_1_PRESENT15,22FAN_1_PRESENT 15,22FAN_2_PRESENT15,22FAN_2_PRESENT 15,22
P3V3_AUXP3V3_AUXP3V3_AUXP3V3_AUXP3V3_AUXP3V3_AUX
P52V_HSCP52V_HSCP52V_FAN_0P52V_HSCP52V_HSCP52V_FAN_1P52V_HSCP52V_HSCP52V_FAN_2SizeDoc NumberRevDate: SheetofReviewerDesignerDepartmentProject
Page TitleBU9<Doc> V00C Monday, August 28, 2023<Designer><Reviewer> 15 25<Title>EFUSE1SizeDoc NumberRevDate: SheetofReviewerDesignerDepartmentProject
Page TitleBU9<Doc> V00C Monday, August 28, 2023<Designer><Reviewer> 15 25<Title>EFUSE1SizeDoc NumberRevDate: SheetofReviewerDesignerDepartmentProject
Page TitleBU9<Doc> V00C Monday, August 28, 2023<Designer><Reviewer> 15 25<Title>EFUSE1PC21191000PFPC25 2.2UFX6S<Part Number>C0402-020110VPR36100KR0402
PC4 2.2UFX6S<Part Number>C0402-020110VU39574LVC1G14GW<Part Number>VCC5A2GND3Y4NC11 PC160.47UFX7RC0805_H61100V<Part Number>10%PR108.25K<Part Number>R0402-02010.1%
PC34 0.01UFX7R<Part Number>C0402-020110%50V
+PC756UF<Part Number>80V20%12PC31190.1UF25VX7RC0402-020110%<Part Number>PR70<Part Number>R0402-0201NIC2069 0.1UFX7R C0402-020110% 16V
PU1MP5048GU-Z<Part Number>VIN11VIN22VIN318VOUT24VOUT35VOUT46VOUT57VOUT68VOUT79VOUT810VOUT911VOUT1012VOUT1113VOUT1214VOUT1315VOUT1416VOUT1517CS19IMON20SS21FAULT22TIMER23CLREF24GND25ON263V275V28VTEMP29MODE30VOUT13C2066 0.1UFX7R C0402-020110% 16VC20962.2UFX7R<Part Number>100V 10%
PC300.47UFX7RC0805_H61100V<Part Number>10%PR350<Part Number>R0402-0201PR38 8.25KR0402-0201 <Part Number>0.1%PC31 2.2UFX6S<Part Number>C0402-020110VU39674LVC1G14GW<Part Number>VCC5A2GND3Y4NC11 PC21201000PFPR29100KR0402-0201<Part Number>1%C2064 0.1UFX7R C0402-020110% 16V+PC2356UF20%ALUM<Part Number>80V12PC27 0.1UFX7RC0402-020110% 25V <Part Number>C2067 0.1UFX7R C0402-020110% 16VC20972.2UFPC26 2.2UFX6S<Part Number>C0402-020110VPU4MP5048GU-Z<Part Number>VIN11VIN22VIN318VOUT24VOUT35VOUT46VOUT57VOUT68VOUT79VOUT810VOUT911VOUT1012VOUT1113VOUT1214VOUT1315VOUT1416VOUT1517CS19IMON20SS21FAULT22TIMER23CLREF24GND25ON263V275V28VTEMP29MODE30VOUT13PR348.25K<Part Number>R0402-02010.1%PR810K<Part Number>R0402-02011%R5420 0C20992.2UFX7R100V10%C1206_H76<Part Number>C2065 0.1UFX7R C0402-020110% 16VC20982.2UF
PC31200.1UF25VX7RC0402-020110%<Part Number>PR37100KR0402-0201<Part Number>1%PR310<Part Number>R0402-0201NIPD1B380-13-F<Part Number>ACPR949.9KR0402-0201<Part Number>1%
PC33 0.1UFX7RC0402-020110% 25V <Part Number>U38174LVC1G08GW<Part Number>12453 C21002.2UFPD35.0SMDJ54AACR5418 0PC32 2.2UFX6S<Part Number>C0402-020110V+PC2956UF20%ALUM<Part Number>80V12PR428.25K<Part Number>R0402-02010.1%
PR3100KR0402
R5421 0PC6 0.01UFX7R<Part Number>C0402-020110%50VPC80.47UFX7RC0805_H61100V<Part Number>10%C21012.2UFPR390<Part Number>R0402-0201NI
R5416 0
PU5MP5048GU-Z<Part Number>VIN11VIN22VIN318VOUT24VOUT35VOUT46VOUT57VOUT68VOUT79VOUT810VOUT911VOUT1012VOUT1113VOUT1214VOUT1315VOUT1416VOUT1517CS19IMON20SS21FAULT22TIMER23CLREF24GND25ON263V275V28VTEMP29MODE30VOUT13U37974LVC1G08GW<Part Number>12453PR3210K<Part Number>R0402-02011%C21022.2UFX7R100V10%C1206_H76<Part Number>PD8B380-13-F<Part Number>ACPD45.0SMDJ54AACR5419 0PR6 8.25KR0402-0201 <Part Number>0.1%PC10.47UFX7RC0805_H61100V<Part Number>10%PC21181000PFU37774LVC1G08GW<Part Number>12453PC3 2.2UFX6S<Part Number>C0402-020110VPR10<Part Number>R0402-0201PR28100KR0402PR3349.9KR0402-0201<Part Number>1%PC90.47UFX7RC0805_H61100V<Part Number>10%C21032.2UF
PC31180.1UF25VX7RC0402-020110%<Part Number>R5417 0U39474LVC1G14GW<Part Number>VCC5A2GND3Y4NC11
PR4010K<Part Number>R0402-02011%C21042.2UFPC28 0.01UFX7R<Part Number>C0402-020110%50VPR5100KR0402-0201<Part Number>1%PR270<Part Number>R0402-0201PD9B380-13-F<Part Number>ACPR4149.9KR0402-0201<Part Number>1%PD65.0SMDJ54AACPC5 0.1UFX7RC0402-020110% 25V <Part Number>PR30 8.25KR0402-0201 <Part Number>0.1%PC240.47UFX7RC0805_H61100V<Part Number>10%C2068 0.1UFX7R C0402-020110% 16V
FAN_0_PRESENT_RP52V_FAN_0_ENFAN_0_PRSNT_BUF_NFAN_0_ONFAN_1_PRSNT_BUF_NFAN_1_PRESENT_RP52V_FAN_1_ENFAN_1_ONFAN_2_PRSNT_BUF_NFAN_2_PRESENT_RP52V_FAN_2_ENFAN_2_ON
P52V_FAN_0_BUFF_EN_RP52V_FAN_1_BUFF_EN_RP52V_FAN_2_BUFF_EN_RNC_U395_P1NC_U396_P1
NC_U394_P1FAN_0_FAULT_RFAN_0_FAULTFAN_0_ONFAN_0_P5VFAN_0_P3V_RFAN_0_MODEFAN_0_TEMPFAN_0_CSFAN_0_CLREFFAN_0_SSFAN_0_IMONFAN_0_TIMERFAN_1_FAULT_RFAN_1_FAULTFAN_1_ONFAN_1_P5VFAN_1_P3V_RFAN_1_MODEFAN_1_TEMPFAN_1_CSFAN_1_CLREFFAN_1_SSFAN_1_IMONFAN_1_TIMERFAN_2_FAULT_RFAN_2_FAULTFAN_2_ONFAN_2_P5VFAN_2_P3V_RFAN_2_MODEFAN_2_TEMPFAN_2_CSFAN_2_CLREFFAN_2_SSFAN_2_IMONFAN_2_TIMER



5
5
4
4
3
3
2
2
1
1
D D
C C
B B
A A
EFUSE2
MODE:PULL MODE HIGH FOR LATCH MODEPULL MODE DOWN FOR HICCUP MODEMODE:PULL MODE HIGH FOR LATCH MODEPULL MODE DOWN FOR HICCUP MODEMODE:PULL MODE HIGH FOR LATCH MODEPULL MODE DOWN FOR HICCUP MODE
Main(MP5048)Soft start: 25msOCP(min/nom/max): 5.84/6.05/6.26A
2nd(MAX17525)Soft start: 24msOCP(min/nom/max): 5.8/6/6.15A
Main(MP5048)Soft start: 25msOCP(min/nom/max): 5.84/6.05/6.26A
2nd(MAX17525)Soft start: 24msOCP(min/nom/max): 5.8/6/6.15A
Main(MP5048)Soft start: 25msOCP(min/nom/max): 5.84/6.05/6.26A
2nd(MAX17525)Soft start: 24msOCP(min/nom/max): 5.8/6/6.15A
FAN_3_PRSNT_BUF_N 9,12FAN_4_PRSNT_BUF_N 10,12FAN_5_PRSNT_BUF_N 10,12
P52V_FAN_3_BUFF_EN_R 14P52V_FAN_4_BUFF_EN_R 14P52V_FAN_5_BUFF_EN_R 14
FAN_3_PRESENT16,22FAN_3_PRESENT 16,22FAN_4_PRESENT16,22FAN_4_PRESENT 16,22FAN_5_PRESENT16,22FAN_5_PRESENT 16,22
P3V3_AUXP3V3_AUXP3V3_AUXP3V3_AUXP3V3_AUXP3V3_AUX
P52V_HSCP52V_HSCP52V_FAN_3P52V_HSCP52V_HSCP52V_FAN_4P52V_HSCP52V_HSCP52V_FAN_5SizeDoc NumberRevDate: SheetofReviewerDesignerDepartmentProject
Page TitleBU9<Doc> V00C Monday, August 28, 2023<Designer><Reviewer> 16 25<Title>EFUSE2SizeDoc NumberRevDate: SheetofReviewerDesignerDepartmentProject
Page TitleBU9<Doc> V00C Monday, August 28, 2023<Designer><Reviewer> 16 25<Title>EFUSE2SizeDoc NumberRevDate: SheetofReviewerDesignerDepartmentProject
Page TitleBU9<Doc> V00C Monday, August 28, 2023<Designer><Reviewer> 16 25<Title>EFUSE2
+PC2256UF20%ALUM<Part Number>80V12PC40 0.1UFX7RC0402-020110% 25V <Part Number>C21062.2UFR5353 0PC39 2.2UFX6S<Part Number>C0402-020110VPU6MP5048GU-Z<Part Number>VIN11VIN22VIN318VOUT24VOUT35VOUT46VOUT57VOUT68VOUT79VOUT810VOUT911VOUT1012VOUT1113VOUT1214VOUT1315VOUT1416VOUT1517CS19IMON20SS21FAULT22TIMER23CLREF24GND25ON263V275V28VTEMP29MODE30VOUT13PR548.25K<Part Number>R0402-02010.1%U36174LVC1G08GW<Part Number>12453
PR4410K<Part Number>R0402-02011%C21072.2UFC21082.2UFX7R<Part Number>C1206_H7610%100VPR510<Part Number>R0402-0201NIPC31230.1UF25VX7RC0402-020110%<Part Number>PR57100KR0402-0201<Part Number>1%C2060 0.1UFX7R C0402-020110% 16VU35974LVC1G08GW<Part Number>12453PR22100KR0402
C2062 0.1UFX7R C0402-020110% 16V
PR4549.9KR0402-0201<Part Number>1%PD145.0SMDJ54AAC
PC46 0.1UFX7RC0402-020110% 25V <Part Number>C21092.2UFPC45 2.2UFX6S<Part Number>C0402-020110VPR628.25K<Part Number>R04020.1%+PC4256UF20%ALUM<Part Number>80V12
PC600.47UFX7RC0805_H61100V<Part Number>10%PC21 0.01UFX7R<Part Number>C0402-020110%50VC21102.2UFC2061 0.1UFX7R C0402-020110% 16V
PR590<Part Number>R0402-0201NI
PC360.47UFX7RC0805_H61100V<Part Number>10%
PU7MP5048GU-Z<Part Number>VIN11VIN22VIN318VOUT24VOUT35VOUT46VOUT57VOUT68VOUT79VOUT810VOUT911VOUT1012VOUT1113VOUT1214VOUT1315VOUT1416VOUT1517CS19IMON20SS21FAULT22TIMER23CLREF24GND25ON263V275V28VTEMP29MODE30VOUT13PR5210K<Part Number>R0402-02011%PD7B380-13-F<Part Number>ACC21112.2UFX7R<Part Number>C1206_H7610%100VPD155.0SMDJ54AACPR26 8.25KR0402-0201 <Part Number>0.1%PR210<Part Number>R0402-0201PC21211000PFPC18 2.2UFX6S<Part Number>C0402-020110VU39174LVC1G14GW<Part Number>VCC5A2GND3Y4NC11 PR48100KR0402R5354 0PD10B380-13-F<Part Number>ACPR5349.9KR0402-0201<Part Number>1%PC610.47UFX7RC0805_H61100V<Part Number>10%C21122.2UF
PC31210.1UF25VX7RC0402-020110%<Part Number>U39274LVC1G14GW<Part Number>VCC5A2GND3Y4NC11 PR6010K<Part Number>R0402-02011%PC41 0.01UFX7R<Part Number>C0402-020110%50VC21132.2UFU39374LVC1G14GW<Part Number>VCC5A2GND3Y4NC11
PR24100KR0402-0201<Part Number>1%PR470<Part Number>R0402-0201PD11B380-13-F<Part Number>AC
U7474LVC1G08GW<Part Number>12453
PR6149.9KR0402-0201<Part Number>1%
PC20 0.1UFX7RC0402-020110% 25V <Part Number>
PD165.0SMDJ54AACPR50 8.25KR0402-0201 <Part Number>0.1%PC370.47UFX7RC0805_H61100V<Part Number>10%R5356 0PC21221000PFPC38 2.2UFX6S<Part Number>C0402-020110VPC19 2.2UFX6S<Part Number>C0402-020110VR503 0PR468.25K<Part Number>R0402-02010.1%+PC3556UF20%ALUM<Part Number>80V12
PR56100KR0402PC620.47UFX7RC0805_H61100V<Part Number>10%PC47 0.01UFX7R<Part Number>C0402-020110%50VPC31220.1UF25VX7RC0402-020110%<Part Number>PR430<Part Number>R0402-0201NIR506 0PU3MP5048GU-Z<Part Number>VIN11VIN22VIN318VOUT24VOUT35VOUT46VOUT57VOUT68VOUT79VOUT810VOUT911VOUT1012VOUT1113VOUT1214VOUT1315VOUT1416VOUT1517CS19IMON20SS21FAULT22TIMER23CLREF24GND25ON263V275V28VTEMP29MODE30VOUT13C165 0.1UFX7R C0402-020110% 16VC21052.2UFX7R<Part Number>C1206_H7610%100V
C2063 0.1UFX7R C0402-020110% 16V
C172 0.1UFX7R C0402-020110% 16V
PR58 8.25KR0402 <Part Number>0.1%R5355 0PC430.47UFX7RC0805_H61100V<Part Number>10%PR550<Part Number>R0402-0201PR49100KR0402-0201<Part Number>1%PC21231000PFPC44 2.2UFX6S<Part Number>C0402-020110V
FAN_3_PRESENT_RP52V_FAN_3_ENFAN_3_PRSNT_BUF_NFAN_3_ONFAN_4_PRSNT_BUF_NFAN_4_PRESENT_RP52V_FAN_4_ENFAN_4_ONFAN_5_PRSNT_BUF_NFAN_5_PRESENT_RP52V_FAN_5_ENFAN_5_ON
P52V_FAN_3_BUFF_EN_RP52V_FAN_4_BUFF_EN_RP52V_FAN_5_BUFF_EN_R
NC_U391_P1NC_U392_P1NC_U393_P1
FAN_3_FAULT_RFAN_3_FAULTFAN_3_ONFAN_3_P5VFAN_3_P3V_RFAN_3_MODEFAN_3_TEMPFAN_3_CSFAN_3_CLREFFAN_3_SSFAN_3_IMONFAN_3_TIMERFAN_4_FAULT_RFAN_4_FAULTFAN_4_ONFAN_4_P5VFAN_4_P3V_RFAN_4_MODEFAN_4_TEMPFAN_4_CSFAN_4_CLREFFAN_4_SSFAN_4_IMONFAN_4_TIMERFAN_5_FAULT_RFAN_5_FAULTFAN_5_ONFAN_5_P5VFAN_5_P3V_RFAN_5_MODEFAN_5_TEMPFAN_5_CSFAN_5_CLREFFAN_5_SSFAN_5_IMONFAN_5_TIMER



5
5
4
4
3
3
2
2
1
1
D D
C C
B B
A A
EFUSE3
MODE:PULL MODE HIGH FOR LATCH MODEPULL MODE DOWN FOR HICCUP MODEMODE:PULL MODE HIGH FOR LATCH MODEPULL MODE DOWN FOR HICCUP MODE
Main(MP5048)Soft start: 25msIMax: 2AOCP(min/nom/max): 5.84/6.05/6.26A
Main(MP5048)Soft start: 25msIMax: 2AOCP(min/nom/max): 5.84/6.05/6.26A
FAN_6_PRSNT_BUF_N 10,12FAN_7_PRSNT_BUF_N 10,12P52V_FAN_6_BUFF_EN_R 14P52V_FAN_7_BUFF_EN_R 14FAN_6_PRESENT17,22FAN_6_PRESENT 17,22FAN_7_PRESENT17,22FAN_7_PRESENT 17,22P3V3_AUXP3V3_AUXP3V3_AUXP3V3_AUXP52V_HSCP52V_HSCP52V_FAN_6P52V_HSCP52V_HSCP52V_FAN_7
SizeDoc NumberRevDate: SheetofReviewerDesignerDepartmentProject
Page TitleBU9<Doc> V00C Monday, August 28, 2023<Designer><Reviewer> 17 25<Title>EFUSE3SizeDoc NumberRevDate: SheetofReviewerDesignerDepartmentProject
Page TitleBU9<Doc> V00C Monday, August 28, 2023<Designer><Reviewer> 17 25<Title>EFUSE3SizeDoc NumberRevDate: SheetofReviewerDesignerDepartmentProject
Page TitleBU9<Doc> V00C Monday, August 28, 2023<Designer><Reviewer> 17 25<Title>EFUSE3
U39874LVC1G14GW<Part Number>VCC5A2GND3Y4NC11 PR708.25K<Part Number>R0402-02010.1%+PC4856UF20%ALUM<Part Number>80V12PC31250.1UF25VX7RC0402-020110%<Part Number>PR670<Part Number>R0402-0201NIR5424 0PU8MP5048GU-Z<Part Number>VIN11VIN22VIN318VOUT24VOUT35VOUT46VOUT57VOUT68VOUT79VOUT810VOUT911VOUT1012VOUT1113VOUT1214VOUT1315VOUT1416VOUT1517CS19IMON20SS21FAULT22TIMER23CLREF24GND25ON263V275V28VTEMP29MODE30VOUT13C21142.2UFX7R<Part Number>C1206_H76100V10%PR73100KR0402-0201<Part Number>1%C2070 0.1UFX7R C0402-020110% 16VU38574LVC1G08GW<Part Number>12453 PC58 0.1UFX7RC0402-020110% 25V <Part Number>+PC5456UF20%ALUM<Part Number>80V12PC57 2.2UFX6S<Part Number>C0402-020110VC21152.2UFPR788.25K<Part Number>R0402-02010.1%R5425 0C2071 0.1UFX7R C0402-020110% 16VPU9MP5048GU-Z<Part Number>VIN11VIN22VIN318VOUT24VOUT35VOUT46VOUT57VOUT68VOUT79VOUT810VOUT911VOUT1012VOUT1113VOUT1214VOUT1315VOUT1416VOUT1517CS19IMON20SS21FAULT22TIMER23CLREF24GND25ON263V275V28VTEMP29MODE30VOUT13PR6810K<Part Number>R0402-02011%PR750<Part Number>R0402-0201NI C21162.2UFC21172.2UFX7R<Part Number>C1206_H76100V10%U39774LVC1G14GW<Part Number>VCC5A2GND3Y4NC11 PD12B380-13-F<Part Number>ACPR6949.9KR0402-0201<Part Number>1%PD175.0SMDJ54A<Part Number>AC C21182.2UFPR64100KR0402PC630.47UFX7RC0805_H61100V<Part Number>10%R5422 0PC53 0.01UFX7R<Part Number>C0402-020110%50VC21192.2UFPR7610K<Part Number>R0402-02011%
U38374LVC1G08GW<Part Number>12453 PD13B380-13-F<Part Number>ACPD185.0SMDJ54A<Part Number>ACPR66 8.25KR0402-0201 <Part Number>0.1%PC490.47UFX7RC0805_H61100V<Part Number>10%PR630<Part Number>R0402-0201PC21241000PFPC50 2.2UFX6S<Part Number>C0402-020110VPR7749.9KR0402-0201<Part Number>1%PR72100KR0402C2072 0.1UFX7R C0402-020110% 16VR5423 0PC640.47UFX7RC0805_H61100V<Part Number>10%PC31240.1UF25VX7RC0402-020110%<Part Number>PC59 0.01UFX7R<Part Number>C0402-020110%50VC2073 0.1UFX7R C0402-020110% 16VPR65100KR0402-0201<Part Number>1%PR710<Part Number>R0402-0201PR74 8.25KR0402-0201 <Part Number>0.1%PC21251000PFPC56 2.2UFX6S<Part Number>C0402-020110VPC52 0.1UFX7RC0402-020110% 25V <Part Number>PC550.47UFX7RC0805_H61100V<Part Number>10%PC51 2.2UFX6S<Part Number>C0402-020110VFAN_6_PRESENT_RP52V_FAN_6_ENFAN_6_PRSNT_BUF_NFAN_6_ONFAN_7_PRSNT_BUF_NFAN_7_PRESENT_RP52V_FAN_7_ENFAN_7_ONP52V_FAN_6_BUFF_EN_RP52V_FAN_7_BUFF_EN_RNC_U397_P1NC_U398_P1FAN_6_FAULT_RFAN_6_FAULTFAN_6_ONFAN_6_P5VFAN_6_P3V_RFAN_6_MODEFAN_6_TEMPFAN_6_CSFAN_6_CLREFFAN_6_SSFAN_6_IMONFAN_6_TIMERFAN_7_FAULT_RFAN_7_FAULTFAN_7_ONFAN_7_P5VFAN_7_P3V_RFAN_7_MODEFAN_7_TEMPFAN_7_CSFAN_7_CLREFFAN_7_SSFAN_7_IMONFAN_7_TIMER



5
5
4
4
3
3
2
2
1
1
D D
C C
B B
A A
IF=2mAVF=2.3VAMBER
IF=1.83mAVF=3.2VBLUE
IF=2mAVF=2.3VAMBER
IF=1.83mAVF=3.2VBLUE
IF=2mAVF=2.3VAMBER
IF=1.83mAVF=3.2VBLUE
IF=1.83mAVF=3.2VBLUE
IF=2mAVF=2.3VAMBER
LED1
Fan_0_FAIL_R_LED12Fan_0_OK_R_LED_N 20Fan_0_FAIL_R_LED_N 20Fan_0_OK_R_LED12Fan_1_OK_R_LED_N 20Fan_1_FAIL_R_LED_N 20Fan_1_OK_R_LED12Fan_1_FAIL_R_LED12Fan_2_OK_R_LED_N 20Fan_2_FAIL_R_LED_N 20Fan_2_OK_R_LED12Fan_2_FAIL_R_LED12Fan_3_OK_R_LED_N 20Fan_3_FAIL_R_LED_N 20Fan_3_OK_R_LED12Fan_3_FAIL_R_LED12
P3V3_AUXP3V3_AUXP3V3_AUXP3V3_AUXP3V3_AUXP3V3_AUXP3V3_AUXP3V3_AUX
P12V_LED_FAN0P12V_LED_FAN1P12V_LED_FAN2P12V_LED_FAN3P12V_LED_FAN3P12V_LED_FAN2P12V_LED_FAN1P12V_LED_FAN0
SizeDoc NumberRevDate: SheetofReviewerDesignerDepartmentProject
Page TitleBU9<Doc> V00C Monday, August 28, 2023<Designer><Reviewer> 18 25<Title>LED1SizeDoc NumberRevDate: SheetofReviewerDesignerDepartmentProject
Page TitleBU9<Doc> V00C Monday, August 28, 2023<Designer><Reviewer> 18 25<Title>LED1SizeDoc NumberRevDate: SheetofReviewerDesignerDepartmentProject
Page TitleBU9<Doc> V00C Monday, August 28, 2023<Designer><Reviewer> 18 25<Title>LED1
R54142.4KR0402R54102.4KR0402
D
G
S
U3732N7002KW<Part Number>DGSR539910K1/16W1%R0402-0201R5528100K1/16W1%R0402R54042.4KR0402
R54002.4KR0402
R54082.4KR0402
R539110K1/16W1%R0402-0201R5530100K1/16W1%R0402
D
G
S
U3712N7002KW<Part Number>DGSR539710K1/16W1%R0402-0201
D
G
S
U3742N7002KW<Part Number>DGS
R5525100K1/16W1%R0402R54122.4KR0402R5532100K1/16W1%R0402
D
G
S
U3682N7002KW<Part Number>DGS R538910K1/16W1%R0402-0201R5527100K1/16W1%R0402R538710K1/16W1%R0402-0201
R539510K1/16W1%R0402-0201R5529100K1/16W1%R0402
D
G
S
U3722N7002KW<Part Number>DGSR54062.4KR0402
D
G
S
U3752N7002KW<Part Number>DGS
R538410K1/16W1%R0402-0201
D
G
S
U3692N7002KW<Part Number>DGS
R5531100K1/16W1%R0402R54022.4KR0402R539310K1/16W1%R0402-0201
R5526100K1/16W1%R0402
D
G
S
U3702N7002KW<Part Number>DGSFan_0_FAIL_R_LEDFan_0_OK_LED_R_NFan_0_FAIl_LED_R_NFan_0_OK_R_LEDFan_1_OK_LED_R_NFan_1_OK_R_LEDFan_1_FAIL_R_LEDFan_2_OK_LED_R_NFan_2_FAIL_LED_R_NFan_2_OK_R_LEDFan_2_FAIL_R_LEDFan_3_OK_LED_R_NFan_3_FAIL_LED_R_NFan_3_OK_R_LEDFan_3_FAIL_R_LED
Fan_1_FAIL_LED_R_N



5
5
4
4
3
3
2
2
1
1
D D
C C
B B
A A
IF=2mAVF=2.3VAMBER
IF=1.83mAVF=3.2VBLUE
IF=2mAVF=2.3VAMBER
IF=1.83mAVF=3.2VBLUE
IF=2mAVF=2.3VAMBER
IF=1.83mAVF=3.2VBLUE
IF=1.83mAVF=3.2VBLUE
IF=2mAVF=2.3VAMBER
LED2
Fan_4_FAIL_R_LED12Fan_4_OK_R_LED_N 21Fan_4_FAIL_R_LED_N 21Fan_4_OK_R_LED12Fan_5_OK_R_LED_N 21Fan_5_FAIL_R_LED_N 21Fan_5_OK_R_LED12Fan_5_FAIL_R_LED12Fan_6_OK_R_LED_N 21Fan_6_FAIL_R_LED_N 21Fan_6_OK_R_LED12Fan_6_FAIL_R_LED12Fan_7_OK_R_LED_N 21Fan_7_FAIL_R_LED_N 21Fan_7_OK_R_LED12Fan_7_FAIL_R_LED12
P3V3_AUXP3V3_AUXP3V3_AUXP3V3_AUXP3V3_AUXP3V3_AUXP3V3_AUXP3V3_AUX
P12V_LED_FAN4P12V_LED_FAN5P12V_LED_FAN6P12V_LED_FAN7P12V_LED_FAN7P12V_LED_FAN6P12V_LED_FAN5P12V_LED_FAN4
SizeDoc NumberRevDate: SheetofReviewerDesignerDepartmentProject
Page TitleBU9<Doc> V00C Monday, August 28, 2023<Designer><Reviewer> 19 25<Title>LED2SizeDoc NumberRevDate: SheetofReviewerDesignerDepartmentProject
Page TitleBU9<Doc> V00C Monday, August 28, 2023<Designer><Reviewer> 19 25<Title>LED2SizeDoc NumberRevDate: SheetofReviewerDesignerDepartmentProject
Page TitleBU9<Doc> V00C Monday, August 28, 2023<Designer><Reviewer> 19 25<Title>LED2
D
G
S
U3672N7002KW<Part Number>DGS
D
G
S
U3622N7002KW<Part Number>DGSR536310K1/16W1%R0402-0201R5533100K1/16W1%R0402
R5540100K1/16W1%R0402
R53822.4KR0402
R499210K1/16W1%R0402-0201R53492.4KR0402R499010K1/16W1%R0402-0201R5535100K1/16W1%R0402
D
G
S
U3662N7002KW<Part Number>DGS
R5537100K1/16W1%R0402
R537910K1/16W1%R0402-0201R537810K1/16W1%R0402-0201
R53662.4KR0402R5539100K1/16W1%R0402
R53742.4KR0402
D
G
S
U3652N7002KW<Part Number>DGSR537010K1/16W1%R0402-0201R53802.4KR0402
D
G
S
U3632N7002KW<Part Number>DGSR536210K1/16W1%R0402-0201R5534100K1/16W1%R0402
D
G
S
U3642N7002KW<Part Number>DGSR53722.4KR0402R537110K1/16W1%R0402-0201R5536100K1/16W1%R0402
D
G
S
U3402N7002KW<Part Number>DGSR53642.4KR0402R5538100K1/16W1%R0402R53582.4KR0402
D
G
S
U3422N7002KW<Part Number>DGSFan_4_FAIL_R_LEDFan_4_OK_LED_R_NFan_4_FAIl_LED_R_NFan_4_OK_R_LEDFan_5_OK_LED_R_NFan_5_FAIl_LED_R_NFan_5_OK_R_LEDFan_5_FAIL_R_LEDFan_6_OK_LED_R_NFan_6_FAIl_LED_R_NFan_6_OK_R_LEDFan_6_FAIL_R_LEDFan_7_OK_LED_R_NFan_7_FAIl_LED_R_NFan_7_OK_R_LEDFan_7_FAIL_R_LED



5
5
4
4
3
3
2
2
1
1
4 4
3 3
2 2
1 1
close to connector J1
close to connector J2
close to connector J3
close to connector J4
Fan_conn1
voltage=52*56.1/106=27.52(V)derating=55.04%voltage=52*56.1/106=27.52(V)derating=55.04%voltage=52*56.1/106=27.52(V)derating=55.04%voltage=52*56.1/106=27.52(V)derating=55.04%
Fan_0_PWM_OL6 Fan_0_TACH_IL 4,5,20FAN_0_PRESENT_R_N9 Fan_0_PWM_IL 6SMB_FAN0_SCL11Fan_0_TACH_OL 4,5,20Fan_1_PWM_OL6 Fan_1_TACH_IL 4,5,20FAN_1_PRESENT_R_N9 Fan_1_PWM_IL 6SMB_FAN1_SCL11Fan_1_TACH_OL 4,5,20Fan_2_PWM_OL6 Fan_2_TACH_IL 4,5,20FAN_2_PRESENT_R_N9 Fan_2_PWM_IL 6SMB_FAN2_SCL11Fan_2_TACH_OL 4,5,20Fan_3_PWM_OL6 Fan_3_TACH_IL 4,5,20FAN_3_PRESENT_R_N9 Fan_3_PWM_IL 6SMB_FAN3_SCL11Fan_3_TACH_OL 4,5,20
Fan_0_FAIL_R_LED_N18,20Fan_0_OK_R_LED_N18,20Fan_1_FAIL_R_LED_N18,20Fan_1_OK_R_LED_N18,20Fan_2_FAIL_R_LED_N18,20Fan_2_OK_R_LED_N18,20Fan_3_FAIL_R_LED_N18,20Fan_3_OK_R_LED_N18,20
SMB_FAN0_SDA 11SMB_FAN1_SDA 11SMB_FAN2_SDA 11SMB_FAN3_SDA 11
Fan_0_OK_R_LED_N18,20Fan_1_OK_R_LED_N18,20Fan_0_FAIL_R_LED_N18,20Fan_1_FAIL_R_LED_N18,20Fan_2_OK_R_LED_N18,20Fan_2_FAIL_R_LED_N18,20Fan_3_OK_R_LED_N18,20Fan_3_FAIL_R_LED_N18,20Fan_3_TACH_OL4,5,20Fan_3_TACH_IL4,5,20Fan_2_TACH_OL4,5,20Fan_2_TACH_IL4,5,20Fan_1_TACH_OL4,5,20Fan_1_TACH_IL4,5,20Fan_0_TACH_OL4,5,20Fan_0_TACH_IL4,5,20
P52V_FAN_0P52V_FAN_0P52V_FAN_0P52V_FAN_1P52V_FAN_1P52V_FAN_1P52V_FAN_2P52V_FAN_2P52V_FAN_2P52V_FAN_3P52V_FAN_3P52V_FAN_3P12V_LED_FAN3P12V_LED_FAN2P12V_LED_FAN1P12V_LED_FAN0
SizeDoc NumberRevDate: SheetofReviewerDesignerDepartmentProject
Page TitleBU9<Doc> V00C Monday, August 28, 2023<Designer><Reviewer> 20 25<Title>FAN_CONNSizeDoc NumberRevDate: SheetofReviewerDesignerDepartmentProject
Page TitleBU9<Doc> V00C Monday, August 28, 2023<Designer><Reviewer> 20 25<Title>FAN_CONNSizeDoc NumberRevDate: SheetofReviewerDesignerDepartmentProject
Page TitleBU9<Doc> V00C Monday, August 28, 2023<Designer><Reviewer> 20 25<Title>FAN_CONN
R5306 100KC201810UF16V10%C0805_H61<Part Number>NIC2023220PF50VC0402-0201<Part Number>R5224 33D269UCLAMP0511TNIACR543212KC202410UF16V10%C0805_H61<Part Number>NIC2040220PF50VC0402-0201<Part Number>R5326 100K
R56901.2KR5307 100KD276UCLAMP0511TNIACJ4CONN16_70127-16C5<Part Number>1133445566778822991010111112121313141415151616J3CONN16_70127-16C5<Part Number>1133445566778822991010111112121313141415151616
C20190.1UF16VC040210%NI
R5220 33R543312K
D270UCLAMP0511TNIACC2041220PF50VC0402-0201R5328100KR0603R5327 100KD139SDMK0340L-7-F12
R56891.2K
D277UCLAMP0511TNIACC20250.1UF16VC040210%NIC2042220PF50VC0402-0201R5329100KR0603D271UCLAMP0511TNIACR5196 33R5202 33
D141SDMK0340L-7-F12
D278UCLAMP0511TNIACC2043220PF50VC0402-0201<Part Number>R5330 100KR5244 33D272UCLAMP0511TNIACR5186 33R5300100KR0603
D279UCLAMP0511TNIACR56911.2K
C2052220PF50VC0402-0201<Part Number>
D132SDMK0340L-7-F12
R5331 100KD273UCLAMP0511TNIAC
R5240 33C2053220PF50VC0402-0201
J2CONN16_70127-16C5<Part Number>1133445566778822991010111112121313141415151616
D280UCLAMP0511TNIACD143SDMK0340L-7-F12
R56921.2KR5302 100KR56931.2K
D281UCLAMP0511TNIACD274UCLAMP0511TNIACD133SDMK0340L-7-F12
D263UCLAMP0511TNIAC
C2054220PF50VC0402-0201C203610UF16V10%C0805_H61<Part Number>NIR56941.2KR5204 33D282UCLAMP0511TNIACR542612KC2055220PF50VC0402-0201<Part Number>D264UCLAMP0511TNIACC2028220PF50VC0402-0201<Part Number>R56951.2K
R5184 33R5187 33
D283UCLAMP0511TNIACC20370.1UF16VC040210%NI R542712KR5303 100KR5200 33C2029220PF50VC0402-0201R5216 33R5222 33
D265UCLAMP0511TNIACD135SDMK0340L-7-F12R5301100KR0603
R56961.2KR542812KD284UCLAMP0511TNIAC
R5188 33C2030220PF50VC0402-0201
D266UCLAMP0511TNIACC2020220PF50VC0402-0201<Part Number>
C204810UF16V10%C0805_H61<Part Number>NI R542912KD285UCLAMP0511TNIACC2031220PF50VC0402-0201<Part Number>J1CONN16_70127-16C5<Part Number>1133445566778822991010111112121313141415151616R5304100KR0603C2021220PF50VC0402-0201
D267UCLAMP0511TNIACD131SDMK0340L-7-F12 R543012KR5324100KR0603
D286UCLAMP0511TNIAC
R5305100KR0603C20490.1UF16VC040210%<Part Number>NI
C2022220PF50VC0402-0201
D268UCLAMP0511TNIAC
D137SDMK0340L-7-F12R5242 33R543112KR5236 33R5325100KR0603<Part Number>D275UCLAMP0511TNIAC
Fan_0_PWM_OL_RFan_0_TACH_IL_DFan_0_TACH_IL_RFAN_0_PRESENT_R_NFan_0_PWM_IL_RSMB_FAN0_SCL_RSMB_FAN0_SDA_RFan_0_FAIL_R_LED_NFan_0_OK_R_LED_NFan_0_TACH_OL_DFan_0_TACH_OL_RFan_1_PWM_OL_RFan_1_TACH_IL_DFan_1_TACH_IL_RFAN_1_PRESENT_R_NFan_1_PWM_IL_RSMB_FAN1_SCL_RSMB_FAN1_SDA_RFan_1_FAIL_R_LED_NFan_1_OK_R_LED_NFan_1_TACH_OL_DFan_1_TACH_OL_RFan_2_PWM_OL_RFan_2_TACH_IL_DFan_2_TACH_IL_RFAN_2_PRESENT_R_NFan_2_PWM_IL_RSMB_FAN2_SCL_RSMB_FAN2_SDA_RFan_2_FAIL_R_LED_NFan_2_OK_R_LED_NFan_2_TACH_OL_DFan_2_TACH_OL_RFan_3_PWM_OL_RFan_3_TACH_IL_DFan_3_TACH_IL_RFAN_3_PRESENT_R_NFan_3_PWM_IL_RSMB_FAN3_SCL_RSMB_FAN3_SDA_RFan_3_FAIL_R_LED_NFan_3_OK_R_LED_NFan_3_TACH_OL_DFan_3_TACH_OL_R
FAN_0_PWM_IL_RFAN_1_PWM_IL_RFAN_0_PWM_OL_RFAN_1_PWM_OL_RFan_0_TACH_IL_DFan_1_TACH_IL_DFan_0_TACH_OL_DFan_1_TACH_OL_DFan_0_OK_R_LED_NFan_1_OK_R_LED_NFan_0_FAIL_R_LED_NFan_1_FAIL_R_LED_NFAN_2_PWM_IL_RFAN_2_PWM_OL_RFan_2_TACH_IL_DFan_2_TACH_OL_DFan_2_OK_R_LED_NFan_2_FAIL_R_LED_NFAN_3_PWM_IL_RFAN_3_PWM_OL_RFan_3_TACH_IL_DFan_3_TACH_OL_DFan_3_OK_R_LED_NFan_3_FAIL_R_LED_NFan_3_TACH_OLFan_3_TACH_ILFan_2_TACH_OLFan_2_TACH_ILFan_1_TACH_OLFan_1_TACH_ILFan_0_TACH_OLFan_0_TACH_ILP12V_LED_R_FAN0P12V_LED_R1_FAN0P12V_LED_R_FAN1P12V_LED_R1_FAN1P12V_LED_R_FAN2P12V_LED_R1_FAN2P12V_LED_R_FAN3P12V_LED_R1_FAN3



5
5
4
4
3
3
2
2
1
1
D D
C C
B B
A A
close to connector J8
close to connector J7
close to connector J5
close to connector J6
Fan_conn2
voltage=52*56.1/106=27.52(V)derating=55.04%voltage=52*56.1/106=27.52(V)derating=55.04%voltage=52*56.1/106=27.52(V)derating=55.04%voltage=52*56.1/106=27.52(V)derating=55.04%
Fan_4_PWM_OL7 Fan_4_TACH_IL 4,5,21FAN_4_PRESENT_R_N10Fan_4_PWM_IL 7SMB_FAN4_SCL11Fan_4_TACH_OL 4,5,21Fan_5_PWM_OL7 Fan_5_TACH_IL 4,5,21FAN_5_PRESENT_R_N10Fan_5_PWM_IL 7SMB_FAN5_SCL11Fan_5_TACH_OL 4,5,21Fan_6_PWM_OL7 Fan_6_TACH_IL 4,5,21FAN_6_PRESENT_R_N10Fan_6_PWM_IL 7SMB_FAN6_SCL11Fan_6_TACH_OL 4,5,21Fan_7_PWM_OL7 Fan_7_TACH_IL 4,5,21FAN_7_PRESENT_R_N10Fan_7_PWM_IL 7SMB_FAN7_SCL11Fan_7_TACH_OL 4,5,21Fan_7_FAIL_R_LED_N19,21Fan_7_OK_R_LED_N19,21Fan_6_FAIL_R_LED_N19,21Fan_6_OK_R_LED_N19,21Fan_5_FAIL_R_LED_N19,21Fan_5_OK_R_LED_N19,21Fan_4_FAIL_R_LED_N19,21Fan_4_OK_R_LED_N19,21
SMB_FAN7_SDA 11SMB_FAN6_SDA 11SMB_FAN5_SDA 11SMB_FAN4_SDA 11Fan_4_OK_R_LED_N19,21Fan_4_FAIL_R_LED_N19,21Fan_5_OK_R_LED_N19,21Fan_5_FAIL_R_LED_N19,21Fan_6_OK_R_LED_N19,21Fan_6_FAIL_R_LED_N19,21Fan_7_OK_R_LED_N19,21Fan_7_FAIL_R_LED_N19,21Fan_7_TACH_OL4,5,21Fan_7_TACH_IL4,5,21Fan_6_TACH_OL4,5,21Fan_6_TACH_IL4,5,21Fan_5_TACH_OL4,5,21Fan_5_TACH_IL4,5,21Fan_4_TACH_OL4,5,21Fan_4_TACH_IL4,5,21
P52V_FAN_4P52V_FAN_4P52V_FAN_4P52V_FAN_5P52V_FAN_5P52V_FAN_5P52V_FAN_6P52V_FAN_6P52V_FAN_6P52V_FAN_7P52V_FAN_7P52V_FAN_7P12V_LED_FAN7P12V_LED_FAN6P12V_LED_FAN5P12V_LED_FAN4
SizeDoc NumberRevDate: SheetofReviewerDesignerDepartmentProject
Page TitleBU9<Doc> V00C Monday, August 28, 2023<Designer><Reviewer> 21 25<Title>FAN_CONN2SizeDoc NumberRevDate: SheetofReviewerDesignerDepartmentProject
Page TitleBU9<Doc> V00C Monday, August 28, 2023<Designer><Reviewer> 21 25<Title>FAN_CONN2SizeDoc NumberRevDate: SheetofReviewerDesignerDepartmentProject
Page TitleBU9<Doc> V00C Monday, August 28, 2023<Designer><Reviewer> 21 25<Title>FAN_CONN2D250UCLAMP0511TNIACR543712KD259UCLAMP0511TNIACR5238 33
R57011.2KR5203 33
D255UCLAMP0511TNIACR5243 33C2034220PF50VC0402-0201C2035220PF50VC0402-0201<Part Number>R543812KC2059220PF50VC0402-0201<Part Number>R5225 33R5312100KR0603
D260UCLAMP0511TNIAC
J5CONN16_70127-16C5<Part Number>1133445566778822991010111112121313141415151616R57021.2KD140SDMK0340L-7-F12R5241 33R5320100KR0603
D256UCLAMP0511TNIACR543912KD134SDMK0340L-7-F12C2033220PF50VC0402-0201
D261UCLAMP0511TNIACR5223 33R5201 33
D144SDMK0340L-7-F12 R544012KC2046220PF50VC0402-0201
C2016220PF50VC0402-0201
J8CONN16_70127-16C5<Part Number>1133445566778822991010111112121313141415151616
C2014220PF50VC0402-0201<Part Number>C2032220PF50VC0402-0201<Part Number>
D239UCLAMP0511TNIACD136SDMK0340L-7-F12
D262UCLAMP0511TNIACC2056220PF50VC0402-0201<Part Number>R56991.2KR544112KC2058220PF50VC0402-0201D138SDMK0340L-7-F12R5321100KR0603
C2015220PF50VC0402-0201
D240UCLAMP0511TNIACR5132 33C20120.1UF16VC040210%NI
C203810UF16V10%C0805_H61<Part Number>NIR5323 100KR56971.2KR57001.2K
D241UCLAMP0511TNIACR5308100KR0603
R5245 33D142SDMK0340L-7-F12
C2017220PF50VC0402-0201<Part Number>R5128 33C20270.1UF16VC040210%NIC20390.1UF16VC040210%NID114SDMK0340L-7-F12
R56981.2KR5318 100KD242UCLAMP0511TNIACD245UCLAMP0511TNIACR5313100KR0603R5205 33
D243UCLAMP0511TNIACD246UCLAMP0511TNIACC202610UF16V10%C0805_H61<Part Number>NI
R5322 100KC2047220PF50VC0402-0201<Part Number>
R57031.2KC15710UF16V10%C0805_H61<Part Number>NI
C20510.1UF16VC040210%NI
D251UCLAMP0511TNIACC2045220PF50VC0402-0201
D244UCLAMP0511TNIACD247UCLAMP0511TNIAC
C2057220PF50VC0402-0201R5221 33R5316100KR0603R5198 33R57041.2KR543412KD252UCLAMP0511TNIAC
R5131 33
R5218 33J7CONN16_70127-16C5<Part Number>1133445566778822991010111112121313141415151616
R5311 100KD248UCLAMP0511TNIACJ6CONN16_70127-16C5<Part Number>1133445566778822991010111112121313141415151616C2044220PF50VC0402-0201<Part Number>
D113SDMK0340L-7-F12
D257UCLAMP0511TNIACR543512KD253UCLAMP0511TNIACC205010UF16V10%C0805_H61<Part Number>NI
D249UCLAMP0511TNIACR5314 100KD258UCLAMP0511TNIACR543612KR5317100KR0603
R5309100KR0603R5315 100KD254UCLAMP0511TNIAC
R5310 100K
R5319 100K
R5130 33Fan_4_PWM_OL_RFan_4_TACH_IL_DFan_4_TACH_IL_RFAN_4_PRESENT_R_NFan_4_PWM_IL_RSMB_FAN4_SCL_RSMB_FAN4_SDA_RFan_4_FAIL_R_LED_NFan_4_OK_R_LED_NFan_4_TACH_OL_DFan_4_TACH_OL_RFan_5_PWM_OL_RFan_5_TACH_IL_DFan_5_TACH_IL_RFAN_5_PRESENT_R_NFan_5_PWM_IL_RSMB_FAN5_SCL_RSMB_FAN5_SDA_RFan_5_FAIL_R_LED_NFan_5_OK_R_LED_NFan_5_TACH_OL_DFan_5_TACH_OL_RFan_6_PWM_OL_RFan_6_TACH_IL_DFan_6_TACH_IL_RFAN_6_PRESENT_R_NFan_6_PWM_IL_RSMB_FAN6_SCL_RSMB_FAN6_SDA_RFan_6_FAIL_R_LED_NFan_6_OK_R_LED_NFan_6_TACH_OL_DFan_6_TACH_OL_RFan_7_PWM_OL_RFan_7_TACH_IL_DFan_7_TACH_IL_RFAN_7_PRESENT_R_NFan_7_PWM_IL_RSMB_FAN7_SCL_RSMB_FAN7_SDA_RFan_7_FAIL_R_LED_NFan_7_OK_R_LED_NFan_7_TACH_OL_DFan_7_TACH_OL_R
FAN_4_PWM_IL_RFAN_4_PWM_OL_RFan_4_TACH_IL_DFan_4_TACH_OL_DFan_4_OK_R_LED_NFan_4_FAIL_R_LED_NFAN_5_PWM_IL_RFAN_5_PWM_OL_RFan_5_TACH_IL_DFan_5_TACH_OL_DFan_5_OK_R_LED_NFan_5_FAIL_R_LED_NFAN_6_PWM_IL_RFAN_6_PWM_OL_RFan_6_TACH_IL_DFan_6_TACH_OL_DFan_6_OK_R_LED_NFan_6_FAIL_R_LED_NFAN_7_PWM_IL_RFAN_7_PWM_OL_RFan_7_TACH_IL_DFan_7_TACH_OL_DFan_7_OK_R_LED_NFan_7_FAIL_R_LED_NFan_7_TACH_OLFan_7_TACH_ILFan_6_TACH_OLFan_6_TACH_ILFan_5_TACH_OLFan_5_TACH_ILFan_4_TACH_OLFan_4_TACH_ILP12V_LED_R_FAN7P12V_LED_R1_FAN7P12V_LED_R_FAN6P12V_LED_R1_FAN6P12V_LED_R_FAN5P12V_LED_R1_FAN5P12V_LED_R_FAN4P12V_LED_R1_FAN4



5
5
4
4
3
3
2
2
1
1
D D
C C
B B
A A
ADC SizeDoc NumberRevDate: SheetofReviewerDesignerDepartmentProject
Page TitleBU9<Doc> V00C Friday, December 02, 2022<Designer><Reviewer> 22 25<Title>ADCSizeDoc NumberRevDate: SheetofReviewerDesignerDepartmentProject
Page TitleBU9<Doc> V00C Friday, December 02, 2022<Designer><Reviewer> 22 25<Title>ADCSizeDoc NumberRevDate: SheetofReviewerDesignerDepartmentProject
Page TitleBU9<Doc> V00C Friday, December 02, 2022<Designer><Reviewer> 22 25<Title>ADC



5
5
4
4
3
3
2
2
1
1
D D
C C
B B
A A
Current limter
FAN_0_PRESENT15FAN_1_PRESENT15FAN_2_PRESENT15FAN_3_PRESENT16FAN_4_PRESENT16FAN_5_PRESENT16FAN_6_PRESENT17FAN_7_PRESENT17P12V_LEDP12V_LED_FAN0P12V_LEDP12V_LED_FAN1P12V_LEDP12V_LED_FAN2P12V_LEDP12V_LED_FAN3P12V_LEDP12V_LED_FAN4P12V_LEDP12V_LED_FAN5P12V_LEDP12V_LED_FAN6P12V_LEDP12V_LED_FAN7
SizeDoc NumberRevDate: SheetofReviewerDesignerDepartmentProject
Page TitleBU9<Doc> V00C Monday, August 28, 2023<Designer><Reviewer> 23 25<Title>current switchSizeDoc NumberRevDate: SheetofReviewerDesignerDepartmentProject
Page TitleBU9<Doc> V00C Monday, August 28, 2023<Designer><Reviewer> 23 25<Title>current switchSizeDoc NumberRevDate: SheetofReviewerDesignerDepartmentProject
Page TitleBU9<Doc> V00C Monday, August 28, 2023<Designer><Reviewer> 23 25<Title>current switch
Q15FDN352AP<Part Number>GDSC212110UFC0603NI<Part Number>20%C212510UFC0603NI<Part Number>20%R56524.7KR04025%
D
G
S
U4092N7002KW<Part Number>DGSR56674.7K5%1/16WR0402-0201
Q10FDN352AP<Part Number>GDSC212610UFC0603NI<Part Number>20%R56534.7KR04025%R56594.7KR04025%
D
G
S
U4102N7002KW<Part Number>DGSQ11FDN352AP<Part Number>GDSQ13FDN352AP<Part Number>GDS R56684.7K5%1/16WR0402-0201C212710UFC0603NI<Part Number>20%R56474.7K5%1/16WR0402-0201
D
G
S
U4112N7002KW<Part Number>DGSQ16FDN352AP<Part Number>GDSR56694.7K5%1/16WR0402-0201R56484.7KR04025% C212310UFC0603NI<Part Number>20%R56604.7KR04025%
D
G
S
U4052N7002KW<Part Number>DGSR56514.7K5%1/16WR0402-0201Q14FDN352AP<Part Number>GDS
D
G
S
U4122N7002KW<Part Number>DGSR56564.7K5%1/16WR0402-0201
D
G
S
U4062N7002KW<Part Number>DGS R56614.7KR04025%Q12FDN352AP<Part Number>GDSQ9FDN352AP<Part Number>GDS
D
G
S
U4072N7002KW<Part Number>DGSR56574.7K5%1/16WR0402-0201R56584.7KR04025%C212010UFC0603NI<Part Number>20%R56494.7KR04025%R56664.7K5%1/16WR0402-0201C212210UFC0603NI<Part Number>20%C212410UFC0603NI<Part Number>20%
D
G
S
U4082N7002KW<Part Number>DGSU405_D1U406_D1U407_D1U408_D1U409_D1U410_D1U411_D1U412_D1



5
5
4
4
3
3
2
2
1
1
D D
C C
B B
A A
Screw
Tooling Hole
Screw Hole Hand Screw Hole
Quanta LOGO(TOP) CE
SN LABEL
Laser Mark(TOP)
WEEE PN LABEL
Laser Mark(BOT)
PCBA_LABEL PB-E1
UL
vendor logo
SN + VPN + QPN
SizeDoc NumberRevDate: SheetofReviewerDesignerDepartmentProject
Page TitleBU9<Doc> V00C Monday, August 28, 2023<Designer><Reviewer> 24 25<Title>SCREWSizeDoc NumberRevDate: SheetofReviewerDesignerDepartmentProject
Page TitleBU9<Doc> V00C Monday, August 28, 2023<Designer><Reviewer> 24 25<Title>SCREWSizeDoc NumberRevDate: SheetofReviewerDesignerDepartmentProject
Page TitleBU9<Doc> V00C Monday, August 28, 2023<Designer><Reviewer> 24 25<Title>SCREW
ME_PART SymbolME5PB-E1_SMALLNI<Part Number>H14HOLE_TOOLINGD125N_T2-0NIH4HOLE_C9D3_5B9_OB12XC4-5_NPM_TEAR_SPDNI
ME_PART SymbolME7SNLABEL_27X6<Part Number>NI
H15HOLE_TOOLINGD125N_T2-0NI ME_PART SymbolME6PCB_VENDOR_LOGO_15X8<Part Number>
H2HOLE_C9D3_5B9_OB12XC4-5_NPM_TEAR_SPDNIH11HOLE_C10-16D6-4B10_OB22XC5B_NPH1HOLE_C9D3_5B9_OB12XC4-5_NPM_TEAR_SPDNI
ME_PART SymbolME3QUANTA_LOGO_7X26NI<Part Number>
H3HOLE_C9D3_5B9_OB12XC4-5_NPM_TEAR_SPDNIH13HOLE_TOOLINGD125N_T2-0NIME_PART SymbolME4WEEENI<Part Number>



5
5
4
4
3
3
2
2
1
1
D D
C C
B B
A A
TDR
BOT
TOP
IN1
TDR-SINGLE
IN2
SizeDoc NumberRevDate: SheetofReviewerDesignerDepartmentProject
Page TitleBU9<Doc> V00C Monday, August 28, 2023<Designer><Reviewer> 25 25<Title>TDRSizeDoc NumberRevDate: SheetofReviewerDesignerDepartmentProject
Page TitleBU9<Doc> V00C Monday, August 28, 2023<Designer><Reviewer> 25 25<Title>TDRSizeDoc NumberRevDate: SheetofReviewerDesignerDepartmentProject
Page TitleBU9<Doc> V00C Monday, August 28, 2023<Designer><Reviewer> 25 25<Title>TDR
J95TDR_3P_C85P67_141_100M_QGND1IO12IO23J83TDR_3P_C85P67_141_100M_QGND1IO12IO23J81TDR_3P_C85P67_141_100M_QGND1IO12IO23J85TDR_3P_C85P67_141_100M_QGND1IO12IO23TDR_SE_50_OHM_TOPTDR_SE_50_OHM_IN1TDR_SE_50_OHM_IN2TDR_SE_50_OHM_BOT